FILE_TYPE = MACRO_DRAWING;
SET COLOR_WIRE YELLOW;
SET COLOR_PROP ORANGE;
SET COLOR_DOT WHITE;
SET COLOR_ARC YELLOW;
SET COLOR_BODY GREEN;
SET COLOR_NOTE PURPLE;
SET PROP_DISPLAY VALUE;
SET PAGE_NUMBER P168;
FORCEADD OFFPAGE..1
(1225 1600);
FORCEPROP 2 LAST $XR0 62 
J 0
(1004 1600);
DISPLAY 0.638298 (1004 1600);
PAINT MONO (1004 1600);
FORCEPROP 2 LAST CDS_LIB standard
J 0
(1225 1600);
DISPLAY INVISIBLE (1225 1600);
FORCEPROP 1 LAST OFFPAGE TRUE
J 0
(1550 1475);
DISPLAY 0.872340 (1550 1475);
DISPLAY INVISIBLE (1550 1475);
FORCEPROP 1 LAST COMMENT_BODY TRUE
J 0
(1350 1500);
DISPLAY 0.872340 (1350 1500);
PAINT GREEN (1350 1500);
DISPLAY INVISIBLE (1350 1500);
FORCEPROP 2 LAST PATH I103
J 0
(1275 1675);
DISPLAY 1.021277 (1275 1675);
DISPLAY INVISIBLE (1275 1675);
FORCEADD OFFPAGE..1
(1225 1550);
FORCEPROP 2 LAST $XR0 62 
J 0
(1004 1550);
DISPLAY 0.638298 (1004 1550);
PAINT MONO (1004 1550);
FORCEPROP 2 LAST CDS_LIB standard
J 0
(1225 1550);
DISPLAY INVISIBLE (1225 1550);
FORCEPROP 1 LAST OFFPAGE TRUE
J 0
(1550 1425);
DISPLAY 0.872340 (1550 1425);
DISPLAY INVISIBLE (1550 1425);
FORCEPROP 1 LAST COMMENT_BODY TRUE
J 0
(1350 1450);
DISPLAY 0.872340 (1350 1450);
PAINT GREEN (1350 1450);
DISPLAY INVISIBLE (1350 1450);
FORCEPROP 2 LAST PATH I104
J 0
(1275 1625);
DISPLAY 1.021277 (1275 1625);
DISPLAY INVISIBLE (1275 1625);
FORCEADD OFFPAGE..1
(1225 3525);
FORCEPROP 2 LAST $XR0 62 
J 0
(1004 3525);
DISPLAY 0.638298 (1004 3525);
PAINT MONO (1004 3525);
FORCEPROP 2 LAST CDS_LIB standard
J 0
(1225 3525);
DISPLAY INVISIBLE (1225 3525);
FORCEPROP 1 LAST OFFPAGE TRUE
J 0
(1550 3400);
DISPLAY 0.872340 (1550 3400);
DISPLAY INVISIBLE (1550 3400);
FORCEPROP 1 LAST COMMENT_BODY TRUE
J 0
(1350 3425);
DISPLAY 0.872340 (1350 3425);
PAINT GREEN (1350 3425);
DISPLAY INVISIBLE (1350 3425);
FORCEPROP 2 LAST PATH I107
J 0
(1275 3600);
DISPLAY 1.021277 (1275 3600);
DISPLAY INVISIBLE (1275 3600);
FORCEADD OFFPAGE..1
(1225 3575);
FORCEPROP 2 LAST $XR0 62 
J 0
(1004 3575);
DISPLAY 0.638298 (1004 3575);
PAINT MONO (1004 3575);
FORCEPROP 2 LAST CDS_LIB standard
J 0
(1225 3575);
DISPLAY INVISIBLE (1225 3575);
FORCEPROP 1 LAST OFFPAGE TRUE
J 0
(1550 3450);
DISPLAY 0.872340 (1550 3450);
DISPLAY INVISIBLE (1550 3450);
FORCEPROP 1 LAST COMMENT_BODY TRUE
J 0
(1350 3475);
DISPLAY 0.872340 (1350 3475);
PAINT GREEN (1350 3475);
DISPLAY INVISIBLE (1350 3475);
FORCEPROP 2 LAST PATH I108
J 0
(1275 3650);
DISPLAY 1.021277 (1275 3650);
DISPLAY INVISIBLE (1275 3650);
FORCEADD TAP..1
R 2
(2175 125);
FORCEPROP 3 LASTPIN (2225 125) SIG_NAME P5E_CPU1_PE4_TX_DP<0>
J 0
(2235 135);
DISPLAY 0.659574 (2235 135);
PAINT MONO (2235 135);
DISPLAY INVISIBLE (2235 135);
FORCEPROP 1 LASTPIN (2225 125) BN 0
J 2
(2237 133);
DISPLAY 0.680851 (2237 133);
PAINT GREEN (2237 133);
FORCEPROP 2 LAST CDS_LIB standard
J 0
(2175 125);
DISPLAY INVISIBLE (2175 125);
FORCEPROP 1 LAST BODY_TYPE PLUMBING
J 2
(2175 175);
DISPLAY 0.872340 (2175 175);
PAINT GREEN (2175 175);
DISPLAY INVISIBLE (2175 175);
FORCEPROP 1 LAST HDL_TAP TRUE
J 2
(1850 0);
DISPLAY 0.872340 (1850 0);
DISPLAY INVISIBLE (1850 0);
FORCEPROP 1 LAST PATH I109
J 2
(2177 125);
DISPLAY 0.872340 (2177 125);
PAINT GREEN (2177 125);
DISPLAY INVISIBLE (2177 125);
FORCEADD TAP..1
R 2
(2175 325);
FORCEPROP 3 LASTPIN (2225 325) SIG_NAME P5E_CPU1_PE4_TX_DP<1>
J 0
(2235 335);
DISPLAY 0.659574 (2235 335);
PAINT MONO (2235 335);
DISPLAY INVISIBLE (2235 335);
FORCEPROP 1 LASTPIN (2225 325) BN 1
J 2
(2237 333);
DISPLAY 0.680851 (2237 333);
PAINT GREEN (2237 333);
FORCEPROP 2 LAST CDS_LIB standard
J 0
(2175 325);
DISPLAY INVISIBLE (2175 325);
FORCEPROP 1 LAST BODY_TYPE PLUMBING
J 2
(2175 375);
DISPLAY 0.872340 (2175 375);
PAINT GREEN (2175 375);
DISPLAY INVISIBLE (2175 375);
FORCEPROP 1 LAST HDL_TAP TRUE
J 2
(1850 200);
DISPLAY 0.872340 (1850 200);
DISPLAY INVISIBLE (1850 200);
FORCEPROP 1 LAST PATH I110
J 2
(2177 325);
DISPLAY 0.872340 (2177 325);
PAINT GREEN (2177 325);
DISPLAY INVISIBLE (2177 325);
FORCEADD TAP..1
R 2
(2425 175);
FORCEPROP 3 LASTPIN (2475 175) SIG_NAME P5E_CPU1_PE4_TX_DN<0>
J 0
(2485 185);
DISPLAY 0.659574 (2485 185);
PAINT MONO (2485 185);
DISPLAY INVISIBLE (2485 185);
FORCEPROP 1 LASTPIN (2475 175) BN 0
J 2
(2487 183);
DISPLAY 0.680851 (2487 183);
PAINT GREEN (2487 183);
FORCEPROP 2 LAST CDS_LIB standard
J 0
(2425 175);
DISPLAY INVISIBLE (2425 175);
FORCEPROP 1 LAST BODY_TYPE PLUMBING
J 2
(2425 225);
DISPLAY 0.872340 (2425 225);
PAINT GREEN (2425 225);
DISPLAY INVISIBLE (2425 225);
FORCEPROP 1 LAST HDL_TAP TRUE
J 2
(2100 50);
DISPLAY 0.872340 (2100 50);
DISPLAY INVISIBLE (2100 50);
FORCEPROP 1 LAST PATH I111
J 2
(2427 175);
DISPLAY 0.872340 (2427 175);
PAINT GREEN (2427 175);
DISPLAY INVISIBLE (2427 175);
FORCEADD TAP..1
R 2
(2425 375);
FORCEPROP 3 LASTPIN (2475 375) SIG_NAME P5E_CPU1_PE4_TX_DN<1>
J 0
(2485 385);
DISPLAY 0.659574 (2485 385);
PAINT MONO (2485 385);
DISPLAY INVISIBLE (2485 385);
FORCEPROP 1 LASTPIN (2475 375) BN 1
J 2
(2487 383);
DISPLAY 0.680851 (2487 383);
PAINT GREEN (2487 383);
FORCEPROP 2 LAST CDS_LIB standard
J 0
(2425 375);
DISPLAY INVISIBLE (2425 375);
FORCEPROP 1 LAST BODY_TYPE PLUMBING
J 2
(2425 425);
DISPLAY 0.872340 (2425 425);
PAINT GREEN (2425 425);
DISPLAY INVISIBLE (2425 425);
FORCEPROP 1 LAST HDL_TAP TRUE
J 2
(2100 250);
DISPLAY 0.872340 (2100 250);
DISPLAY INVISIBLE (2100 250);
FORCEPROP 1 LAST PATH I112
J 2
(2427 375);
DISPLAY 0.872340 (2427 375);
PAINT GREEN (2427 375);
DISPLAY INVISIBLE (2427 375);
FORCEADD TAP..1
R 2
(2175 525);
FORCEPROP 3 LASTPIN (2225 525) SIG_NAME P5E_CPU1_PE4_TX_DP<2>
J 0
(2235 535);
DISPLAY 0.659574 (2235 535);
PAINT MONO (2235 535);
DISPLAY INVISIBLE (2235 535);
FORCEPROP 1 LASTPIN (2225 525) BN 2
J 2
(2237 533);
DISPLAY 0.680851 (2237 533);
PAINT GREEN (2237 533);
FORCEPROP 2 LAST CDS_LIB standard
J 0
(2175 525);
DISPLAY INVISIBLE (2175 525);
FORCEPROP 1 LAST BODY_TYPE PLUMBING
J 2
(2175 575);
DISPLAY 0.872340 (2175 575);
PAINT GREEN (2175 575);
DISPLAY INVISIBLE (2175 575);
FORCEPROP 1 LAST HDL_TAP TRUE
J 2
(1850 400);
DISPLAY 0.872340 (1850 400);
DISPLAY INVISIBLE (1850 400);
FORCEPROP 1 LAST PATH I113
J 2
(2177 525);
DISPLAY 0.872340 (2177 525);
PAINT GREEN (2177 525);
DISPLAY INVISIBLE (2177 525);
FORCEADD TAP..1
R 2
(2175 925);
FORCEPROP 3 LASTPIN (2225 925) SIG_NAME P5E_CPU1_PE4_TX_DP<4>
J 0
(2235 935);
DISPLAY 0.659574 (2235 935);
PAINT MONO (2235 935);
DISPLAY INVISIBLE (2235 935);
FORCEPROP 1 LASTPIN (2225 925) BN 4
J 2
(2237 933);
DISPLAY 0.680851 (2237 933);
PAINT GREEN (2237 933);
FORCEPROP 2 LAST CDS_LIB standard
J 0
(2175 925);
DISPLAY INVISIBLE (2175 925);
FORCEPROP 1 LAST BODY_TYPE PLUMBING
J 2
(2175 975);
DISPLAY 0.872340 (2175 975);
PAINT GREEN (2175 975);
DISPLAY INVISIBLE (2175 975);
FORCEPROP 1 LAST HDL_TAP TRUE
J 2
(1850 800);
DISPLAY 0.872340 (1850 800);
DISPLAY INVISIBLE (1850 800);
FORCEPROP 1 LAST PATH I114
J 2
(2177 925);
DISPLAY 0.872340 (2177 925);
PAINT GREEN (2177 925);
DISPLAY INVISIBLE (2177 925);
FORCEADD TAP..1
R 2
(2175 725);
FORCEPROP 3 LASTPIN (2225 725) SIG_NAME P5E_CPU1_PE4_TX_DP<3>
J 0
(2235 735);
DISPLAY 0.659574 (2235 735);
PAINT MONO (2235 735);
DISPLAY INVISIBLE (2235 735);
FORCEPROP 1 LASTPIN (2225 725) BN 3
J 2
(2237 733);
DISPLAY 0.680851 (2237 733);
PAINT GREEN (2237 733);
FORCEPROP 2 LAST CDS_LIB standard
J 0
(2175 725);
DISPLAY INVISIBLE (2175 725);
FORCEPROP 1 LAST BODY_TYPE PLUMBING
J 2
(2175 775);
DISPLAY 0.872340 (2175 775);
PAINT GREEN (2175 775);
DISPLAY INVISIBLE (2175 775);
FORCEPROP 1 LAST HDL_TAP TRUE
J 2
(1850 600);
DISPLAY 0.872340 (1850 600);
DISPLAY INVISIBLE (1850 600);
FORCEPROP 1 LAST PATH I115
J 2
(2177 725);
DISPLAY 0.872340 (2177 725);
PAINT GREEN (2177 725);
DISPLAY INVISIBLE (2177 725);
FORCEADD TAP..1
R 2
(2425 575);
FORCEPROP 3 LASTPIN (2475 575) SIG_NAME P5E_CPU1_PE4_TX_DN<2>
J 0
(2485 585);
DISPLAY 0.659574 (2485 585);
PAINT MONO (2485 585);
DISPLAY INVISIBLE (2485 585);
FORCEPROP 1 LASTPIN (2475 575) BN 2
J 2
(2487 583);
DISPLAY 0.680851 (2487 583);
PAINT GREEN (2487 583);
FORCEPROP 2 LAST CDS_LIB standard
J 0
(2425 575);
DISPLAY INVISIBLE (2425 575);
FORCEPROP 1 LAST BODY_TYPE PLUMBING
J 2
(2425 625);
DISPLAY 0.872340 (2425 625);
PAINT GREEN (2425 625);
DISPLAY INVISIBLE (2425 625);
FORCEPROP 1 LAST HDL_TAP TRUE
J 2
(2100 450);
DISPLAY 0.872340 (2100 450);
DISPLAY INVISIBLE (2100 450);
FORCEPROP 1 LAST PATH I116
J 2
(2427 575);
DISPLAY 0.872340 (2427 575);
PAINT GREEN (2427 575);
DISPLAY INVISIBLE (2427 575);
FORCEADD TAP..1
R 2
(2425 775);
FORCEPROP 3 LASTPIN (2475 775) SIG_NAME P5E_CPU1_PE4_TX_DN<3>
J 0
(2485 785);
DISPLAY 0.659574 (2485 785);
PAINT MONO (2485 785);
DISPLAY INVISIBLE (2485 785);
FORCEPROP 1 LASTPIN (2475 775) BN 3
J 2
(2487 783);
DISPLAY 0.680851 (2487 783);
PAINT GREEN (2487 783);
FORCEPROP 2 LAST CDS_LIB standard
J 0
(2425 775);
DISPLAY INVISIBLE (2425 775);
FORCEPROP 1 LAST BODY_TYPE PLUMBING
J 2
(2425 825);
DISPLAY 0.872340 (2425 825);
PAINT GREEN (2425 825);
DISPLAY INVISIBLE (2425 825);
FORCEPROP 1 LAST HDL_TAP TRUE
J 2
(2100 650);
DISPLAY 0.872340 (2100 650);
DISPLAY INVISIBLE (2100 650);
FORCEPROP 1 LAST PATH I117
J 2
(2427 775);
DISPLAY 0.872340 (2427 775);
PAINT GREEN (2427 775);
DISPLAY INVISIBLE (2427 775);
FORCEADD TAP..1
R 2
(2175 1125);
FORCEPROP 3 LASTPIN (2225 1125) SIG_NAME P5E_CPU1_PE4_TX_DP<5>
J 0
(2235 1135);
DISPLAY 0.659574 (2235 1135);
PAINT MONO (2235 1135);
DISPLAY INVISIBLE (2235 1135);
FORCEPROP 1 LASTPIN (2225 1125) BN 5
J 2
(2237 1133);
DISPLAY 0.680851 (2237 1133);
PAINT GREEN (2237 1133);
FORCEPROP 2 LAST CDS_LIB standard
J 0
(2175 1125);
DISPLAY INVISIBLE (2175 1125);
FORCEPROP 1 LAST BODY_TYPE PLUMBING
J 2
(2175 1175);
DISPLAY 0.872340 (2175 1175);
PAINT GREEN (2175 1175);
DISPLAY INVISIBLE (2175 1175);
FORCEPROP 1 LAST HDL_TAP TRUE
J 2
(1850 1000);
DISPLAY 0.872340 (1850 1000);
DISPLAY INVISIBLE (1850 1000);
FORCEPROP 1 LAST PATH I118
J 2
(2177 1125);
DISPLAY 0.872340 (2177 1125);
PAINT GREEN (2177 1125);
DISPLAY INVISIBLE (2177 1125);
FORCEADD TAP..1
R 2
(2175 1325);
FORCEPROP 3 LASTPIN (2225 1325) SIG_NAME P5E_CPU1_PE4_TX_DP<6>
J 0
(2235 1335);
DISPLAY 0.659574 (2235 1335);
PAINT MONO (2235 1335);
DISPLAY INVISIBLE (2235 1335);
FORCEPROP 1 LASTPIN (2225 1325) BN 6
J 2
(2237 1333);
DISPLAY 0.680851 (2237 1333);
PAINT GREEN (2237 1333);
FORCEPROP 2 LAST CDS_LIB standard
J 0
(2175 1325);
DISPLAY INVISIBLE (2175 1325);
FORCEPROP 1 LAST BODY_TYPE PLUMBING
J 2
(2175 1375);
DISPLAY 0.872340 (2175 1375);
PAINT GREEN (2175 1375);
DISPLAY INVISIBLE (2175 1375);
FORCEPROP 1 LAST HDL_TAP TRUE
J 2
(1850 1200);
DISPLAY 0.872340 (1850 1200);
DISPLAY INVISIBLE (1850 1200);
FORCEPROP 1 LAST PATH I119
J 2
(2177 1325);
DISPLAY 0.872340 (2177 1325);
PAINT GREEN (2177 1325);
DISPLAY INVISIBLE (2177 1325);
FORCEADD TAP..1
R 2
(2425 975);
FORCEPROP 3 LASTPIN (2475 975) SIG_NAME P5E_CPU1_PE4_TX_DN<4>
J 0
(2485 985);
DISPLAY 0.659574 (2485 985);
PAINT MONO (2485 985);
DISPLAY INVISIBLE (2485 985);
FORCEPROP 1 LASTPIN (2475 975) BN 4
J 2
(2487 983);
DISPLAY 0.680851 (2487 983);
PAINT GREEN (2487 983);
FORCEPROP 2 LAST CDS_LIB standard
J 0
(2425 975);
DISPLAY INVISIBLE (2425 975);
FORCEPROP 1 LAST BODY_TYPE PLUMBING
J 2
(2425 1025);
DISPLAY 0.872340 (2425 1025);
PAINT GREEN (2425 1025);
DISPLAY INVISIBLE (2425 1025);
FORCEPROP 1 LAST HDL_TAP TRUE
J 2
(2100 850);
DISPLAY 0.872340 (2100 850);
DISPLAY INVISIBLE (2100 850);
FORCEPROP 1 LAST PATH I120
J 2
(2427 975);
DISPLAY 0.872340 (2427 975);
PAINT GREEN (2427 975);
DISPLAY INVISIBLE (2427 975);
FORCEADD TAP..1
R 2
(2425 1175);
FORCEPROP 3 LASTPIN (2475 1175) SIG_NAME P5E_CPU1_PE4_TX_DN<5>
J 0
(2485 1185);
DISPLAY 0.659574 (2485 1185);
PAINT MONO (2485 1185);
DISPLAY INVISIBLE (2485 1185);
FORCEPROP 1 LASTPIN (2475 1175) BN 5
J 2
(2487 1183);
DISPLAY 0.680851 (2487 1183);
PAINT GREEN (2487 1183);
FORCEPROP 2 LAST CDS_LIB standard
J 0
(2425 1175);
DISPLAY INVISIBLE (2425 1175);
FORCEPROP 1 LAST BODY_TYPE PLUMBING
J 2
(2425 1225);
DISPLAY 0.872340 (2425 1225);
PAINT GREEN (2425 1225);
DISPLAY INVISIBLE (2425 1225);
FORCEPROP 1 LAST HDL_TAP TRUE
J 2
(2100 1050);
DISPLAY 0.872340 (2100 1050);
DISPLAY INVISIBLE (2100 1050);
FORCEPROP 1 LAST PATH I121
J 2
(2427 1175);
DISPLAY 0.872340 (2427 1175);
PAINT GREEN (2427 1175);
DISPLAY INVISIBLE (2427 1175);
FORCEADD TAP..1
R 2
(2425 1375);
FORCEPROP 3 LASTPIN (2475 1375) SIG_NAME P5E_CPU1_PE4_TX_DN<6>
J 0
(2485 1385);
DISPLAY 0.659574 (2485 1385);
PAINT MONO (2485 1385);
DISPLAY INVISIBLE (2485 1385);
FORCEPROP 1 LASTPIN (2475 1375) BN 6
J 2
(2487 1383);
DISPLAY 0.680851 (2487 1383);
PAINT GREEN (2487 1383);
FORCEPROP 2 LAST CDS_LIB standard
J 0
(2425 1375);
DISPLAY INVISIBLE (2425 1375);
FORCEPROP 1 LAST BODY_TYPE PLUMBING
J 2
(2425 1425);
DISPLAY 0.872340 (2425 1425);
PAINT GREEN (2425 1425);
DISPLAY INVISIBLE (2425 1425);
FORCEPROP 1 LAST HDL_TAP TRUE
J 2
(2100 1250);
DISPLAY 0.872340 (2100 1250);
DISPLAY INVISIBLE (2100 1250);
FORCEPROP 1 LAST PATH I122
J 2
(2427 1375);
DISPLAY 0.872340 (2427 1375);
PAINT GREEN (2427 1375);
DISPLAY INVISIBLE (2427 1375);
FORCEADD TAP..1
R 2
(2175 1525);
FORCEPROP 3 LASTPIN (2225 1525) SIG_NAME P5E_CPU1_PE4_TX_DP<7>
J 0
(2235 1535);
DISPLAY 0.659574 (2235 1535);
PAINT MONO (2235 1535);
DISPLAY INVISIBLE (2235 1535);
FORCEPROP 1 LASTPIN (2225 1525) BN 7
J 2
(2237 1533);
DISPLAY 0.680851 (2237 1533);
PAINT GREEN (2237 1533);
FORCEPROP 2 LAST CDS_LIB standard
J 0
(2175 1525);
DISPLAY INVISIBLE (2175 1525);
FORCEPROP 1 LAST BODY_TYPE PLUMBING
J 2
(2175 1575);
DISPLAY 0.872340 (2175 1575);
PAINT GREEN (2175 1575);
DISPLAY INVISIBLE (2175 1575);
FORCEPROP 1 LAST HDL_TAP TRUE
J 2
(1850 1400);
DISPLAY 0.872340 (1850 1400);
DISPLAY INVISIBLE (1850 1400);
FORCEPROP 1 LAST PATH I123
J 2
(2177 1525);
DISPLAY 0.872340 (2177 1525);
PAINT GREEN (2177 1525);
DISPLAY INVISIBLE (2177 1525);
FORCEADD TAP..1
R 2
(2425 1575);
FORCEPROP 3 LASTPIN (2475 1575) SIG_NAME P5E_CPU1_PE4_TX_DN<7>
J 0
(2485 1585);
DISPLAY 0.659574 (2485 1585);
PAINT MONO (2485 1585);
DISPLAY INVISIBLE (2485 1585);
FORCEPROP 1 LASTPIN (2475 1575) BN 7
J 2
(2487 1583);
DISPLAY 0.680851 (2487 1583);
PAINT GREEN (2487 1583);
FORCEPROP 2 LAST CDS_LIB standard
J 0
(2425 1575);
DISPLAY INVISIBLE (2425 1575);
FORCEPROP 1 LAST BODY_TYPE PLUMBING
J 2
(2425 1625);
DISPLAY 0.872340 (2425 1625);
PAINT GREEN (2425 1625);
DISPLAY INVISIBLE (2425 1625);
FORCEPROP 1 LAST HDL_TAP TRUE
J 2
(2100 1450);
DISPLAY 0.872340 (2100 1450);
DISPLAY INVISIBLE (2100 1450);
FORCEPROP 1 LAST PATH I124
J 2
(2427 1575);
DISPLAY 0.872340 (2427 1575);
PAINT GREEN (2427 1575);
DISPLAY INVISIBLE (2427 1575);
FORCEADD Q_CAP_DIFFBUS..2
R 2
(3150 175);
FORCEPROP 1 LAST PART_NUMBER SP_CH4221MEE01
J 2
(3034 263);
DISPLAY 0.574468 (3034 263);
PAINT GREEN (3034 263);
DISPLAY INVISIBLE (3034 263);
FORCEPROP 2 LAST VALUE DIFF BUS_0.22UF
J 2
(3000 175);
DISPLAY 0.553191 (3000 175);
FORCEPROP 1 LAST $LOCATION C708
J 2
(3384 192);
DISPLAY 0.723404 (3384 192);
PAINT GREEN (3384 192);
FORCEPROP 2 LASTPIN (3225 175) $PN 1
J 0
(3235 185);
DISPLAY 0.808511 (3235 185);
FORCEPROP 2 LASTPIN (3075 175) $PN 2
J 2
(3065 185);
DISPLAY 0.808511 (3065 185);
FORCEPROP 2 LAST TOLERANCE 20%
J 2
(3075 225);
DISPLAY 0.553191 (3075 225);
DISPLAY INVISIBLE (3075 225);
FORCEPROP 2 LAST PACK_TYPE C0201
J 2
(2975 225);
DISPLAY 0.553191 (2975 225);
DISPLAY INVISIBLE (2975 225);
FORCEPROP 1 LAST MATERIAL X6S
J 2
(3159 254);
DISPLAY 0.574468 (3159 254);
PAINT GREEN (3159 254);
DISPLAY INVISIBLE (3159 254);
FORCEPROP 2 LAST VOLTAGE 6.3V
J 2
(2800 225);
DISPLAY 0.553191 (2800 225);
DISPLAY INVISIBLE (2800 225);
FORCEPROP 1 LAST CDS_LMAN_SYM_OUTLINE -25,50,25,-50
J 2
(3150 175);
DISPLAY 0.468085 (3150 175);
PAINT GREEN (3150 175);
DISPLAY INVISIBLE (3150 175);
FORCEPROP 2 LAST CDS_LIB pure_quanta
J 2
(3150 175);
DISPLAY INVISIBLE (3150 175);
FORCEPROP 1 LAST PIN_NAMES_ROTATE TRUE
J 2
(3150 175);
DISPLAY 0.489362 (3150 175);
PAINT GREEN (3150 175);
DISPLAY INVISIBLE (3150 175);
FORCEPROP 1 LAST PATH I125
J 2
(3150 175);
DISPLAY 0.723404 (3150 175);
DISPLAY INVISIBLE (3150 175);
FORCEPROP 1 LAST $LOCATION C708
J 0
(3400 250);
DISPLAY 1.021277 (3400 250);
DISPLAY INVISIBLE (3400 250);
FORCEPROP 2 LAST CDS_LOCATION C708
J 0
(3400 250);
DISPLAY 1.021277 (3400 250);
DISPLAY INVISIBLE (3400 250);
FORCEPROP 2 LAST $SEC 1
J 2
(3325 250);
DISPLAY 0.680851 (3325 250);
PAINT MONO (3325 250);
DISPLAY INVISIBLE (3325 250);
FORCEPROP 2 LAST CDS_SEC 1
J 2
(3325 250);
DISPLAY 0.680851 (3325 250);
DISPLAY INVISIBLE (3325 250);
FORCEADD Q_CAP_DIFFBUS..2
R 2
(3150 125);
FORCEPROP 1 LAST PART_NUMBER SP_CH4221MEE01
J 2
(3034 213);
DISPLAY 0.574468 (3034 213);
PAINT GREEN (3034 213);
DISPLAY INVISIBLE (3034 213);
FORCEPROP 2 LAST VALUE DIFF BUS_0.22UF
J 2
(3000 125);
DISPLAY 0.553191 (3000 125);
FORCEPROP 1 LAST $LOCATION C709
J 2
(3384 142);
DISPLAY 0.723404 (3384 142);
PAINT GREEN (3384 142);
FORCEPROP 2 LASTPIN (3225 125) $PN 1
J 0
(3235 135);
DISPLAY 0.808511 (3235 135);
FORCEPROP 2 LASTPIN (3075 125) $PN 2
J 2
(3065 135);
DISPLAY 0.808511 (3065 135);
FORCEPROP 2 LAST TOLERANCE 20%
J 2
(3075 175);
DISPLAY 0.553191 (3075 175);
DISPLAY INVISIBLE (3075 175);
FORCEPROP 2 LAST PACK_TYPE C0201
J 2
(2975 175);
DISPLAY 0.553191 (2975 175);
DISPLAY INVISIBLE (2975 175);
FORCEPROP 1 LAST MATERIAL X6S
J 2
(3159 204);
DISPLAY 0.574468 (3159 204);
PAINT GREEN (3159 204);
DISPLAY INVISIBLE (3159 204);
FORCEPROP 2 LAST VOLTAGE 6.3V
J 2
(2800 175);
DISPLAY 0.553191 (2800 175);
DISPLAY INVISIBLE (2800 175);
FORCEPROP 1 LAST CDS_LMAN_SYM_OUTLINE -25,50,25,-50
J 2
(3150 125);
DISPLAY 0.468085 (3150 125);
PAINT GREEN (3150 125);
DISPLAY INVISIBLE (3150 125);
FORCEPROP 2 LAST CDS_LIB pure_quanta
J 2
(3150 125);
DISPLAY INVISIBLE (3150 125);
FORCEPROP 1 LAST PIN_NAMES_ROTATE TRUE
J 2
(3150 125);
DISPLAY 0.489362 (3150 125);
PAINT GREEN (3150 125);
DISPLAY INVISIBLE (3150 125);
FORCEPROP 1 LAST PATH I126
J 2
(3150 125);
DISPLAY 0.723404 (3150 125);
DISPLAY INVISIBLE (3150 125);
FORCEPROP 1 LAST $LOCATION C709
J 0
(3400 200);
DISPLAY 1.021277 (3400 200);
DISPLAY INVISIBLE (3400 200);
FORCEPROP 2 LAST CDS_LOCATION C709
J 0
(3400 200);
DISPLAY 1.021277 (3400 200);
DISPLAY INVISIBLE (3400 200);
FORCEPROP 2 LAST $SEC 1
J 2
(3325 200);
DISPLAY 0.680851 (3325 200);
PAINT MONO (3325 200);
DISPLAY INVISIBLE (3325 200);
FORCEPROP 2 LAST CDS_SEC 1
J 2
(3325 200);
DISPLAY 0.680851 (3325 200);
DISPLAY INVISIBLE (3325 200);
FORCEADD Q_CAP_DIFFBUS..2
R 2
(3150 375);
FORCEPROP 1 LAST PART_NUMBER SP_CH4221MEE01
J 2
(3034 463);
DISPLAY 0.574468 (3034 463);
PAINT GREEN (3034 463);
DISPLAY INVISIBLE (3034 463);
FORCEPROP 2 LAST VALUE DIFF BUS_0.22UF
J 2
(3000 375);
DISPLAY 0.553191 (3000 375);
FORCEPROP 1 LAST $LOCATION C706
J 2
(3384 392);
DISPLAY 0.723404 (3384 392);
PAINT GREEN (3384 392);
FORCEPROP 2 LASTPIN (3225 375) $PN 1
J 0
(3235 385);
DISPLAY 0.808511 (3235 385);
FORCEPROP 2 LASTPIN (3075 375) $PN 2
J 2
(3065 385);
DISPLAY 0.808511 (3065 385);
FORCEPROP 2 LAST TOLERANCE 20%
J 2
(3075 425);
DISPLAY 0.553191 (3075 425);
DISPLAY INVISIBLE (3075 425);
FORCEPROP 2 LAST PACK_TYPE C0201
J 2
(2975 425);
DISPLAY 0.553191 (2975 425);
DISPLAY INVISIBLE (2975 425);
FORCEPROP 1 LAST MATERIAL X6S
J 2
(3159 454);
DISPLAY 0.574468 (3159 454);
PAINT GREEN (3159 454);
DISPLAY INVISIBLE (3159 454);
FORCEPROP 2 LAST VOLTAGE 6.3V
J 2
(2800 425);
DISPLAY 0.553191 (2800 425);
DISPLAY INVISIBLE (2800 425);
FORCEPROP 2 LAST CDS_LIB pure_quanta
J 2
(3150 375);
DISPLAY INVISIBLE (3150 375);
FORCEPROP 1 LAST CDS_LMAN_SYM_OUTLINE -25,50,25,-50
J 2
(3150 375);
DISPLAY 0.468085 (3150 375);
PAINT GREEN (3150 375);
DISPLAY INVISIBLE (3150 375);
FORCEPROP 1 LAST PIN_NAMES_ROTATE TRUE
J 2
(3150 375);
DISPLAY 0.489362 (3150 375);
PAINT GREEN (3150 375);
DISPLAY INVISIBLE (3150 375);
FORCEPROP 1 LAST PATH I127
J 2
(3150 375);
DISPLAY 0.723404 (3150 375);
DISPLAY INVISIBLE (3150 375);
FORCEPROP 1 LAST $LOCATION C706
J 0
(3400 450);
DISPLAY 1.021277 (3400 450);
DISPLAY INVISIBLE (3400 450);
FORCEPROP 2 LAST CDS_LOCATION C706
J 0
(3400 450);
DISPLAY 1.021277 (3400 450);
DISPLAY INVISIBLE (3400 450);
FORCEPROP 2 LAST $SEC 1
J 2
(3325 450);
DISPLAY 0.680851 (3325 450);
PAINT MONO (3325 450);
DISPLAY INVISIBLE (3325 450);
FORCEPROP 2 LAST CDS_SEC 1
J 2
(3325 450);
DISPLAY 0.680851 (3325 450);
DISPLAY INVISIBLE (3325 450);
FORCEADD Q_CAP_DIFFBUS..2
R 2
(3150 325);
FORCEPROP 1 LAST PART_NUMBER SP_CH4221MEE01
J 2
(3034 413);
DISPLAY 0.574468 (3034 413);
PAINT GREEN (3034 413);
DISPLAY INVISIBLE (3034 413);
FORCEPROP 2 LAST VALUE DIFF BUS_0.22UF
J 2
(3000 325);
DISPLAY 0.553191 (3000 325);
FORCEPROP 1 LAST $LOCATION C707
J 2
(3384 342);
DISPLAY 0.723404 (3384 342);
PAINT GREEN (3384 342);
FORCEPROP 2 LASTPIN (3225 325) $PN 1
J 0
(3235 335);
DISPLAY 0.808511 (3235 335);
FORCEPROP 2 LASTPIN (3075 325) $PN 2
J 2
(3065 335);
DISPLAY 0.808511 (3065 335);
FORCEPROP 2 LAST TOLERANCE 20%
J 2
(3075 375);
DISPLAY 0.553191 (3075 375);
DISPLAY INVISIBLE (3075 375);
FORCEPROP 2 LAST PACK_TYPE C0201
J 2
(2975 375);
DISPLAY 0.553191 (2975 375);
DISPLAY INVISIBLE (2975 375);
FORCEPROP 1 LAST MATERIAL X6S
J 2
(3159 404);
DISPLAY 0.574468 (3159 404);
PAINT GREEN (3159 404);
DISPLAY INVISIBLE (3159 404);
FORCEPROP 2 LAST VOLTAGE 6.3V
J 2
(2800 375);
DISPLAY 0.553191 (2800 375);
DISPLAY INVISIBLE (2800 375);
FORCEPROP 1 LAST CDS_LMAN_SYM_OUTLINE -25,50,25,-50
J 2
(3150 325);
DISPLAY 0.468085 (3150 325);
PAINT GREEN (3150 325);
DISPLAY INVISIBLE (3150 325);
FORCEPROP 2 LAST CDS_LIB pure_quanta
J 2
(3150 325);
DISPLAY INVISIBLE (3150 325);
FORCEPROP 1 LAST PIN_NAMES_ROTATE TRUE
J 2
(3150 325);
DISPLAY 0.489362 (3150 325);
PAINT GREEN (3150 325);
DISPLAY INVISIBLE (3150 325);
FORCEPROP 1 LAST PATH I128
J 2
(3150 325);
DISPLAY 0.723404 (3150 325);
DISPLAY INVISIBLE (3150 325);
FORCEPROP 1 LAST $LOCATION C707
J 0
(3400 400);
DISPLAY 1.021277 (3400 400);
DISPLAY INVISIBLE (3400 400);
FORCEPROP 2 LAST CDS_LOCATION C707
J 0
(3400 400);
DISPLAY 1.021277 (3400 400);
DISPLAY INVISIBLE (3400 400);
FORCEPROP 2 LAST $SEC 1
J 2
(3325 400);
DISPLAY 0.680851 (3325 400);
PAINT MONO (3325 400);
DISPLAY INVISIBLE (3325 400);
FORCEPROP 2 LAST CDS_SEC 1
J 2
(3325 400);
DISPLAY 0.680851 (3325 400);
DISPLAY INVISIBLE (3325 400);
FORCEADD Q_CAP_DIFFBUS..2
R 2
(3150 575);
FORCEPROP 1 LAST PART_NUMBER SP_CH4221MEE01
J 2
(3034 663);
DISPLAY 0.574468 (3034 663);
PAINT GREEN (3034 663);
DISPLAY INVISIBLE (3034 663);
FORCEPROP 2 LAST VALUE DIFF BUS_0.22UF
J 2
(3000 575);
DISPLAY 0.553191 (3000 575);
FORCEPROP 1 LAST $LOCATION C704
J 2
(3384 592);
DISPLAY 0.723404 (3384 592);
PAINT GREEN (3384 592);
FORCEPROP 2 LASTPIN (3225 575) $PN 1
J 0
(3235 585);
DISPLAY 0.808511 (3235 585);
FORCEPROP 2 LASTPIN (3075 575) $PN 2
J 2
(3065 585);
DISPLAY 0.808511 (3065 585);
FORCEPROP 2 LAST TOLERANCE 20%
J 2
(3075 625);
DISPLAY 0.553191 (3075 625);
DISPLAY INVISIBLE (3075 625);
FORCEPROP 2 LAST PACK_TYPE C0201
J 2
(2975 625);
DISPLAY 0.553191 (2975 625);
DISPLAY INVISIBLE (2975 625);
FORCEPROP 1 LAST MATERIAL X6S
J 2
(3159 654);
DISPLAY 0.574468 (3159 654);
PAINT GREEN (3159 654);
DISPLAY INVISIBLE (3159 654);
FORCEPROP 2 LAST VOLTAGE 6.3V
J 2
(2800 625);
DISPLAY 0.553191 (2800 625);
DISPLAY INVISIBLE (2800 625);
FORCEPROP 1 LAST CDS_LMAN_SYM_OUTLINE -25,50,25,-50
J 2
(3150 575);
DISPLAY 0.468085 (3150 575);
PAINT GREEN (3150 575);
DISPLAY INVISIBLE (3150 575);
FORCEPROP 2 LAST CDS_LIB pure_quanta
J 2
(3150 575);
DISPLAY INVISIBLE (3150 575);
FORCEPROP 1 LAST PIN_NAMES_ROTATE TRUE
J 2
(3150 575);
DISPLAY 0.489362 (3150 575);
PAINT GREEN (3150 575);
DISPLAY INVISIBLE (3150 575);
FORCEPROP 1 LAST PATH I129
J 2
(3150 575);
DISPLAY 0.723404 (3150 575);
DISPLAY INVISIBLE (3150 575);
FORCEPROP 1 LAST $LOCATION C704
J 0
(3400 650);
DISPLAY 1.021277 (3400 650);
DISPLAY INVISIBLE (3400 650);
FORCEPROP 2 LAST CDS_LOCATION C704
J 0
(3400 650);
DISPLAY 1.021277 (3400 650);
DISPLAY INVISIBLE (3400 650);
FORCEPROP 2 LAST $SEC 1
J 2
(3325 650);
DISPLAY 0.680851 (3325 650);
PAINT MONO (3325 650);
DISPLAY INVISIBLE (3325 650);
FORCEPROP 2 LAST CDS_SEC 1
J 2
(3325 650);
DISPLAY 0.680851 (3325 650);
DISPLAY INVISIBLE (3325 650);
FORCEADD Q_CAP_DIFFBUS..2
R 2
(3150 525);
FORCEPROP 1 LAST PART_NUMBER SP_CH4221MEE01
J 2
(3034 613);
DISPLAY 0.574468 (3034 613);
PAINT GREEN (3034 613);
DISPLAY INVISIBLE (3034 613);
FORCEPROP 2 LAST VALUE DIFF BUS_0.22UF
J 2
(3000 525);
DISPLAY 0.553191 (3000 525);
FORCEPROP 1 LAST $LOCATION C705
J 2
(3384 542);
DISPLAY 0.723404 (3384 542);
PAINT GREEN (3384 542);
FORCEPROP 2 LASTPIN (3225 525) $PN 1
J 0
(3235 535);
DISPLAY 0.808511 (3235 535);
FORCEPROP 2 LASTPIN (3075 525) $PN 2
J 2
(3065 535);
DISPLAY 0.808511 (3065 535);
FORCEPROP 2 LAST TOLERANCE 20%
J 2
(3075 575);
DISPLAY 0.553191 (3075 575);
DISPLAY INVISIBLE (3075 575);
FORCEPROP 2 LAST PACK_TYPE C0201
J 2
(2975 575);
DISPLAY 0.553191 (2975 575);
DISPLAY INVISIBLE (2975 575);
FORCEPROP 1 LAST MATERIAL X6S
J 2
(3159 604);
DISPLAY 0.574468 (3159 604);
PAINT GREEN (3159 604);
DISPLAY INVISIBLE (3159 604);
FORCEPROP 2 LAST VOLTAGE 6.3V
J 2
(2800 575);
DISPLAY 0.553191 (2800 575);
DISPLAY INVISIBLE (2800 575);
FORCEPROP 1 LAST CDS_LMAN_SYM_OUTLINE -25,50,25,-50
J 2
(3150 525);
DISPLAY 0.468085 (3150 525);
PAINT GREEN (3150 525);
DISPLAY INVISIBLE (3150 525);
FORCEPROP 2 LAST CDS_LIB pure_quanta
J 2
(3150 525);
DISPLAY INVISIBLE (3150 525);
FORCEPROP 1 LAST PIN_NAMES_ROTATE TRUE
J 2
(3150 525);
DISPLAY 0.489362 (3150 525);
PAINT GREEN (3150 525);
DISPLAY INVISIBLE (3150 525);
FORCEPROP 1 LAST PATH I130
J 2
(3150 525);
DISPLAY 0.723404 (3150 525);
DISPLAY INVISIBLE (3150 525);
FORCEPROP 1 LAST $LOCATION C705
J 0
(3400 600);
DISPLAY 1.021277 (3400 600);
DISPLAY INVISIBLE (3400 600);
FORCEPROP 2 LAST CDS_LOCATION C705
J 0
(3400 600);
DISPLAY 1.021277 (3400 600);
DISPLAY INVISIBLE (3400 600);
FORCEPROP 2 LAST $SEC 1
J 2
(3325 600);
DISPLAY 0.680851 (3325 600);
PAINT MONO (3325 600);
DISPLAY INVISIBLE (3325 600);
FORCEPROP 2 LAST CDS_SEC 1
J 2
(3325 600);
DISPLAY 0.680851 (3325 600);
DISPLAY INVISIBLE (3325 600);
FORCEADD Q_CAP_DIFFBUS..2
R 2
(3150 925);
FORCEPROP 1 LAST PART_NUMBER SP_CH4221MEE01
J 2
(3034 1013);
DISPLAY 0.574468 (3034 1013);
PAINT GREEN (3034 1013);
DISPLAY INVISIBLE (3034 1013);
FORCEPROP 2 LAST VALUE DIFF BUS_0.22UF
J 2
(3000 925);
DISPLAY 0.553191 (3000 925);
FORCEPROP 1 LAST $LOCATION C701
J 2
(3384 942);
DISPLAY 0.723404 (3384 942);
PAINT GREEN (3384 942);
FORCEPROP 2 LASTPIN (3225 925) $PN 1
J 0
(3235 935);
DISPLAY 0.808511 (3235 935);
FORCEPROP 2 LASTPIN (3075 925) $PN 2
J 2
(3065 935);
DISPLAY 0.808511 (3065 935);
FORCEPROP 2 LAST TOLERANCE 20%
J 2
(3075 975);
DISPLAY 0.553191 (3075 975);
DISPLAY INVISIBLE (3075 975);
FORCEPROP 2 LAST PACK_TYPE C0201
J 2
(2975 975);
DISPLAY 0.553191 (2975 975);
DISPLAY INVISIBLE (2975 975);
FORCEPROP 1 LAST MATERIAL X6S
J 2
(3159 1004);
DISPLAY 0.574468 (3159 1004);
PAINT GREEN (3159 1004);
DISPLAY INVISIBLE (3159 1004);
FORCEPROP 2 LAST VOLTAGE 6.3V
J 2
(2800 975);
DISPLAY 0.553191 (2800 975);
DISPLAY INVISIBLE (2800 975);
FORCEPROP 1 LAST CDS_LMAN_SYM_OUTLINE -25,50,25,-50
J 2
(3150 925);
DISPLAY 0.468085 (3150 925);
PAINT GREEN (3150 925);
DISPLAY INVISIBLE (3150 925);
FORCEPROP 2 LAST CDS_LIB pure_quanta
J 2
(3150 925);
DISPLAY INVISIBLE (3150 925);
FORCEPROP 1 LAST PIN_NAMES_ROTATE TRUE
J 2
(3150 925);
DISPLAY 0.489362 (3150 925);
PAINT GREEN (3150 925);
DISPLAY INVISIBLE (3150 925);
FORCEPROP 1 LAST PATH I131
J 2
(3150 925);
DISPLAY 0.723404 (3150 925);
DISPLAY INVISIBLE (3150 925);
FORCEPROP 1 LAST $LOCATION C701
J 0
(3400 1000);
DISPLAY 1.021277 (3400 1000);
DISPLAY INVISIBLE (3400 1000);
FORCEPROP 2 LAST CDS_LOCATION C701
J 0
(3400 1000);
DISPLAY 1.021277 (3400 1000);
DISPLAY INVISIBLE (3400 1000);
FORCEPROP 2 LAST $SEC 1
J 2
(3325 1000);
DISPLAY 0.680851 (3325 1000);
PAINT MONO (3325 1000);
DISPLAY INVISIBLE (3325 1000);
FORCEPROP 2 LAST CDS_SEC 1
J 2
(3325 1000);
DISPLAY 0.680851 (3325 1000);
DISPLAY INVISIBLE (3325 1000);
FORCEADD Q_CAP_DIFFBUS..2
R 2
(3150 775);
FORCEPROP 1 LAST PART_NUMBER SP_CH4221MEE01
J 2
(3034 863);
DISPLAY 0.574468 (3034 863);
PAINT GREEN (3034 863);
DISPLAY INVISIBLE (3034 863);
FORCEPROP 2 LAST VALUE DIFF BUS_0.22UF
J 2
(3000 775);
DISPLAY 0.553191 (3000 775);
FORCEPROP 1 LAST $LOCATION C702
J 2
(3384 792);
DISPLAY 0.723404 (3384 792);
PAINT GREEN (3384 792);
FORCEPROP 2 LASTPIN (3225 775) $PN 1
J 0
(3235 785);
DISPLAY 0.808511 (3235 785);
FORCEPROP 2 LASTPIN (3075 775) $PN 2
J 2
(3065 785);
DISPLAY 0.808511 (3065 785);
FORCEPROP 2 LAST TOLERANCE 20%
J 2
(3075 825);
DISPLAY 0.553191 (3075 825);
DISPLAY INVISIBLE (3075 825);
FORCEPROP 2 LAST PACK_TYPE C0201
J 2
(2975 825);
DISPLAY 0.553191 (2975 825);
DISPLAY INVISIBLE (2975 825);
FORCEPROP 1 LAST MATERIAL X6S
J 2
(3159 854);
DISPLAY 0.574468 (3159 854);
PAINT GREEN (3159 854);
DISPLAY INVISIBLE (3159 854);
FORCEPROP 2 LAST VOLTAGE 6.3V
J 2
(2800 825);
DISPLAY 0.553191 (2800 825);
DISPLAY INVISIBLE (2800 825);
FORCEPROP 2 LAST CDS_LIB pure_quanta
J 2
(3150 775);
DISPLAY INVISIBLE (3150 775);
FORCEPROP 1 LAST CDS_LMAN_SYM_OUTLINE -25,50,25,-50
J 2
(3150 775);
DISPLAY 0.468085 (3150 775);
PAINT GREEN (3150 775);
DISPLAY INVISIBLE (3150 775);
FORCEPROP 1 LAST PIN_NAMES_ROTATE TRUE
J 2
(3150 775);
DISPLAY 0.489362 (3150 775);
PAINT GREEN (3150 775);
DISPLAY INVISIBLE (3150 775);
FORCEPROP 1 LAST PATH I132
J 2
(3150 775);
DISPLAY 0.723404 (3150 775);
DISPLAY INVISIBLE (3150 775);
FORCEPROP 1 LAST $LOCATION C702
J 0
(3400 850);
DISPLAY 1.021277 (3400 850);
DISPLAY INVISIBLE (3400 850);
FORCEPROP 2 LAST CDS_LOCATION C702
J 0
(3400 850);
DISPLAY 1.021277 (3400 850);
DISPLAY INVISIBLE (3400 850);
FORCEPROP 2 LAST $SEC 1
J 2
(3325 850);
DISPLAY 0.680851 (3325 850);
PAINT MONO (3325 850);
DISPLAY INVISIBLE (3325 850);
FORCEPROP 2 LAST CDS_SEC 1
J 2
(3325 850);
DISPLAY 0.680851 (3325 850);
DISPLAY INVISIBLE (3325 850);
FORCEADD Q_CAP_DIFFBUS..2
R 2
(3150 725);
FORCEPROP 1 LAST PART_NUMBER SP_CH4221MEE01
J 2
(3034 813);
DISPLAY 0.574468 (3034 813);
PAINT GREEN (3034 813);
DISPLAY INVISIBLE (3034 813);
FORCEPROP 2 LAST VALUE DIFF BUS_0.22UF
J 2
(3000 725);
DISPLAY 0.553191 (3000 725);
FORCEPROP 1 LAST $LOCATION C703
J 2
(3384 742);
DISPLAY 0.723404 (3384 742);
PAINT GREEN (3384 742);
FORCEPROP 2 LASTPIN (3225 725) $PN 1
J 0
(3235 735);
DISPLAY 0.808511 (3235 735);
FORCEPROP 2 LASTPIN (3075 725) $PN 2
J 2
(3065 735);
DISPLAY 0.808511 (3065 735);
FORCEPROP 2 LAST TOLERANCE 20%
J 2
(3075 775);
DISPLAY 0.553191 (3075 775);
DISPLAY INVISIBLE (3075 775);
FORCEPROP 2 LAST PACK_TYPE C0201
J 2
(2975 775);
DISPLAY 0.553191 (2975 775);
DISPLAY INVISIBLE (2975 775);
FORCEPROP 1 LAST MATERIAL X6S
J 2
(3159 804);
DISPLAY 0.574468 (3159 804);
PAINT GREEN (3159 804);
DISPLAY INVISIBLE (3159 804);
FORCEPROP 2 LAST VOLTAGE 6.3V
J 2
(2800 775);
DISPLAY 0.553191 (2800 775);
DISPLAY INVISIBLE (2800 775);
FORCEPROP 2 LAST CDS_LIB pure_quanta
J 2
(3150 725);
DISPLAY INVISIBLE (3150 725);
FORCEPROP 1 LAST CDS_LMAN_SYM_OUTLINE -25,50,25,-50
J 2
(3150 725);
DISPLAY 0.468085 (3150 725);
PAINT GREEN (3150 725);
DISPLAY INVISIBLE (3150 725);
FORCEPROP 1 LAST PIN_NAMES_ROTATE TRUE
J 2
(3150 725);
DISPLAY 0.489362 (3150 725);
PAINT GREEN (3150 725);
DISPLAY INVISIBLE (3150 725);
FORCEPROP 1 LAST PATH I133
J 2
(3150 725);
DISPLAY 0.723404 (3150 725);
DISPLAY INVISIBLE (3150 725);
FORCEPROP 1 LAST $LOCATION C703
J 0
(3400 800);
DISPLAY 1.021277 (3400 800);
DISPLAY INVISIBLE (3400 800);
FORCEPROP 2 LAST CDS_LOCATION C703
J 0
(3400 800);
DISPLAY 1.021277 (3400 800);
DISPLAY INVISIBLE (3400 800);
FORCEPROP 2 LAST $SEC 1
J 2
(3325 800);
DISPLAY 0.680851 (3325 800);
PAINT MONO (3325 800);
DISPLAY INVISIBLE (3325 800);
FORCEPROP 2 LAST CDS_SEC 1
J 2
(3325 800);
DISPLAY 0.680851 (3325 800);
DISPLAY INVISIBLE (3325 800);
FORCEADD Q_CAP_DIFFBUS..2
R 2
(3150 975);
FORCEPROP 1 LAST PART_NUMBER SP_CH4221MEE01
J 2
(3034 1063);
DISPLAY 0.574468 (3034 1063);
PAINT GREEN (3034 1063);
DISPLAY INVISIBLE (3034 1063);
FORCEPROP 2 LAST VALUE DIFF BUS_0.22UF
J 2
(3000 975);
DISPLAY 0.553191 (3000 975);
FORCEPROP 1 LAST $LOCATION C700
J 2
(3384 992);
DISPLAY 0.723404 (3384 992);
PAINT GREEN (3384 992);
FORCEPROP 2 LASTPIN (3225 975) $PN 1
J 0
(3235 985);
DISPLAY 0.808511 (3235 985);
FORCEPROP 2 LASTPIN (3075 975) $PN 2
J 2
(3065 985);
DISPLAY 0.808511 (3065 985);
FORCEPROP 2 LAST TOLERANCE 20%
J 2
(3075 1025);
DISPLAY 0.553191 (3075 1025);
DISPLAY INVISIBLE (3075 1025);
FORCEPROP 2 LAST PACK_TYPE C0201
J 2
(2975 1025);
DISPLAY 0.553191 (2975 1025);
DISPLAY INVISIBLE (2975 1025);
FORCEPROP 1 LAST MATERIAL X6S
J 2
(3159 1054);
DISPLAY 0.574468 (3159 1054);
PAINT GREEN (3159 1054);
DISPLAY INVISIBLE (3159 1054);
FORCEPROP 2 LAST VOLTAGE 6.3V
J 2
(2800 1025);
DISPLAY 0.553191 (2800 1025);
DISPLAY INVISIBLE (2800 1025);
FORCEPROP 1 LAST CDS_LMAN_SYM_OUTLINE -25,50,25,-50
J 2
(3150 975);
DISPLAY 0.468085 (3150 975);
PAINT GREEN (3150 975);
DISPLAY INVISIBLE (3150 975);
FORCEPROP 2 LAST CDS_LIB pure_quanta
J 2
(3150 975);
DISPLAY INVISIBLE (3150 975);
FORCEPROP 1 LAST PIN_NAMES_ROTATE TRUE
J 2
(3150 975);
DISPLAY 0.489362 (3150 975);
PAINT GREEN (3150 975);
DISPLAY INVISIBLE (3150 975);
FORCEPROP 1 LAST PATH I134
J 2
(3150 975);
DISPLAY 0.723404 (3150 975);
DISPLAY INVISIBLE (3150 975);
FORCEPROP 1 LAST $LOCATION C700
J 0
(3400 1050);
DISPLAY 1.021277 (3400 1050);
DISPLAY INVISIBLE (3400 1050);
FORCEPROP 2 LAST CDS_LOCATION C700
J 0
(3400 1050);
DISPLAY 1.021277 (3400 1050);
DISPLAY INVISIBLE (3400 1050);
FORCEPROP 2 LAST $SEC 1
J 2
(3325 1050);
DISPLAY 0.680851 (3325 1050);
PAINT MONO (3325 1050);
DISPLAY INVISIBLE (3325 1050);
FORCEPROP 2 LAST CDS_SEC 1
J 2
(3325 1050);
DISPLAY 0.680851 (3325 1050);
DISPLAY INVISIBLE (3325 1050);
FORCEADD Q_CAP_DIFFBUS..2
R 2
(3150 1175);
FORCEPROP 1 LAST PART_NUMBER SP_CH4221MEE01
J 2
(3034 1263);
DISPLAY 0.574468 (3034 1263);
PAINT GREEN (3034 1263);
DISPLAY INVISIBLE (3034 1263);
FORCEPROP 2 LAST VALUE DIFF BUS_0.22UF
J 2
(3000 1175);
DISPLAY 0.553191 (3000 1175);
FORCEPROP 1 LAST $LOCATION C698
J 2
(3384 1192);
DISPLAY 0.723404 (3384 1192);
PAINT GREEN (3384 1192);
FORCEPROP 2 LASTPIN (3225 1175) $PN 1
J 0
(3235 1185);
DISPLAY 0.808511 (3235 1185);
FORCEPROP 2 LASTPIN (3075 1175) $PN 2
J 2
(3065 1185);
DISPLAY 0.808511 (3065 1185);
FORCEPROP 2 LAST TOLERANCE 20%
J 2
(3075 1225);
DISPLAY 0.553191 (3075 1225);
DISPLAY INVISIBLE (3075 1225);
FORCEPROP 2 LAST PACK_TYPE C0201
J 2
(2975 1225);
DISPLAY 0.553191 (2975 1225);
DISPLAY INVISIBLE (2975 1225);
FORCEPROP 1 LAST MATERIAL X6S
J 2
(3159 1254);
DISPLAY 0.574468 (3159 1254);
PAINT GREEN (3159 1254);
DISPLAY INVISIBLE (3159 1254);
FORCEPROP 2 LAST VOLTAGE 6.3V
J 2
(2800 1225);
DISPLAY 0.553191 (2800 1225);
DISPLAY INVISIBLE (2800 1225);
FORCEPROP 1 LAST CDS_LMAN_SYM_OUTLINE -25,50,25,-50
J 2
(3150 1175);
DISPLAY 0.468085 (3150 1175);
PAINT GREEN (3150 1175);
DISPLAY INVISIBLE (3150 1175);
FORCEPROP 2 LAST CDS_LIB pure_quanta
J 2
(3150 1175);
DISPLAY INVISIBLE (3150 1175);
FORCEPROP 1 LAST PIN_NAMES_ROTATE TRUE
J 2
(3150 1175);
DISPLAY 0.489362 (3150 1175);
PAINT GREEN (3150 1175);
DISPLAY INVISIBLE (3150 1175);
FORCEPROP 1 LAST PATH I135
J 2
(3150 1175);
DISPLAY 0.723404 (3150 1175);
DISPLAY INVISIBLE (3150 1175);
FORCEPROP 1 LAST $LOCATION C698
J 0
(3400 1250);
DISPLAY 1.021277 (3400 1250);
DISPLAY INVISIBLE (3400 1250);
FORCEPROP 2 LAST CDS_LOCATION C698
J 0
(3400 1250);
DISPLAY 1.021277 (3400 1250);
DISPLAY INVISIBLE (3400 1250);
FORCEPROP 2 LAST $SEC 1
J 2
(3325 1250);
DISPLAY 0.680851 (3325 1250);
PAINT MONO (3325 1250);
DISPLAY INVISIBLE (3325 1250);
FORCEPROP 2 LAST CDS_SEC 1
J 2
(3325 1250);
DISPLAY 0.680851 (3325 1250);
DISPLAY INVISIBLE (3325 1250);
FORCEADD Q_CAP_DIFFBUS..2
R 2
(3150 1125);
FORCEPROP 1 LAST PART_NUMBER SP_CH4221MEE01
J 2
(3034 1213);
DISPLAY 0.574468 (3034 1213);
PAINT GREEN (3034 1213);
DISPLAY INVISIBLE (3034 1213);
FORCEPROP 2 LAST VALUE DIFF BUS_0.22UF
J 2
(3000 1125);
DISPLAY 0.553191 (3000 1125);
FORCEPROP 1 LAST $LOCATION C699
J 2
(3384 1142);
DISPLAY 0.723404 (3384 1142);
PAINT GREEN (3384 1142);
FORCEPROP 2 LASTPIN (3225 1125) $PN 1
J 0
(3235 1135);
DISPLAY 0.808511 (3235 1135);
FORCEPROP 2 LASTPIN (3075 1125) $PN 2
J 2
(3065 1135);
DISPLAY 0.808511 (3065 1135);
FORCEPROP 2 LAST TOLERANCE 20%
J 2
(3075 1175);
DISPLAY 0.553191 (3075 1175);
DISPLAY INVISIBLE (3075 1175);
FORCEPROP 2 LAST PACK_TYPE C0201
J 2
(2975 1175);
DISPLAY 0.553191 (2975 1175);
DISPLAY INVISIBLE (2975 1175);
FORCEPROP 1 LAST MATERIAL X6S
J 2
(3159 1204);
DISPLAY 0.574468 (3159 1204);
PAINT GREEN (3159 1204);
DISPLAY INVISIBLE (3159 1204);
FORCEPROP 2 LAST VOLTAGE 6.3V
J 2
(2800 1175);
DISPLAY 0.553191 (2800 1175);
DISPLAY INVISIBLE (2800 1175);
FORCEPROP 1 LAST CDS_LMAN_SYM_OUTLINE -25,50,25,-50
J 2
(3150 1125);
DISPLAY 0.468085 (3150 1125);
PAINT GREEN (3150 1125);
DISPLAY INVISIBLE (3150 1125);
FORCEPROP 2 LAST CDS_LIB pure_quanta
J 2
(3150 1125);
DISPLAY INVISIBLE (3150 1125);
FORCEPROP 1 LAST PIN_NAMES_ROTATE TRUE
J 2
(3150 1125);
DISPLAY 0.489362 (3150 1125);
PAINT GREEN (3150 1125);
DISPLAY INVISIBLE (3150 1125);
FORCEPROP 1 LAST PATH I136
J 2
(3150 1125);
DISPLAY 0.723404 (3150 1125);
DISPLAY INVISIBLE (3150 1125);
FORCEPROP 1 LAST $LOCATION C699
J 0
(3400 1200);
DISPLAY 1.021277 (3400 1200);
DISPLAY INVISIBLE (3400 1200);
FORCEPROP 2 LAST CDS_LOCATION C699
J 0
(3400 1200);
DISPLAY 1.021277 (3400 1200);
DISPLAY INVISIBLE (3400 1200);
FORCEPROP 2 LAST $SEC 1
J 2
(3325 1200);
DISPLAY 0.680851 (3325 1200);
PAINT MONO (3325 1200);
DISPLAY INVISIBLE (3325 1200);
FORCEPROP 2 LAST CDS_SEC 1
J 2
(3325 1200);
DISPLAY 0.680851 (3325 1200);
DISPLAY INVISIBLE (3325 1200);
FORCEADD Q_CAP_DIFFBUS..2
R 2
(3150 1375);
FORCEPROP 1 LAST PART_NUMBER SP_CH4221MEE01
J 2
(3034 1463);
DISPLAY 0.574468 (3034 1463);
PAINT GREEN (3034 1463);
DISPLAY INVISIBLE (3034 1463);
FORCEPROP 2 LAST VALUE DIFF BUS_0.22UF
J 2
(3000 1375);
DISPLAY 0.553191 (3000 1375);
FORCEPROP 1 LAST $LOCATION C696
J 2
(3384 1392);
DISPLAY 0.723404 (3384 1392);
PAINT GREEN (3384 1392);
FORCEPROP 2 LASTPIN (3225 1375) $PN 1
J 0
(3235 1385);
DISPLAY 0.808511 (3235 1385);
FORCEPROP 2 LASTPIN (3075 1375) $PN 2
J 2
(3065 1385);
DISPLAY 0.808511 (3065 1385);
FORCEPROP 2 LAST TOLERANCE 20%
J 2
(3075 1425);
DISPLAY 0.553191 (3075 1425);
DISPLAY INVISIBLE (3075 1425);
FORCEPROP 2 LAST PACK_TYPE C0201
J 2
(2975 1425);
DISPLAY 0.553191 (2975 1425);
DISPLAY INVISIBLE (2975 1425);
FORCEPROP 1 LAST MATERIAL X6S
J 2
(3159 1454);
DISPLAY 0.574468 (3159 1454);
PAINT GREEN (3159 1454);
DISPLAY INVISIBLE (3159 1454);
FORCEPROP 2 LAST VOLTAGE 6.3V
J 2
(2800 1425);
DISPLAY 0.553191 (2800 1425);
DISPLAY INVISIBLE (2800 1425);
FORCEPROP 1 LAST CDS_LMAN_SYM_OUTLINE -25,50,25,-50
J 2
(3150 1375);
DISPLAY 0.468085 (3150 1375);
PAINT GREEN (3150 1375);
DISPLAY INVISIBLE (3150 1375);
FORCEPROP 2 LAST CDS_LIB pure_quanta
J 2
(3150 1375);
DISPLAY INVISIBLE (3150 1375);
FORCEPROP 1 LAST PIN_NAMES_ROTATE TRUE
J 2
(3150 1375);
DISPLAY 0.489362 (3150 1375);
PAINT GREEN (3150 1375);
DISPLAY INVISIBLE (3150 1375);
FORCEPROP 1 LAST PATH I137
J 2
(3150 1375);
DISPLAY 0.723404 (3150 1375);
DISPLAY INVISIBLE (3150 1375);
FORCEPROP 1 LAST $LOCATION C696
J 0
(3400 1450);
DISPLAY 1.021277 (3400 1450);
DISPLAY INVISIBLE (3400 1450);
FORCEPROP 2 LAST CDS_LOCATION C696
J 0
(3400 1450);
DISPLAY 1.021277 (3400 1450);
DISPLAY INVISIBLE (3400 1450);
FORCEPROP 2 LAST $SEC 1
J 2
(3325 1450);
DISPLAY 0.680851 (3325 1450);
PAINT MONO (3325 1450);
DISPLAY INVISIBLE (3325 1450);
FORCEPROP 2 LAST CDS_SEC 1
J 2
(3325 1450);
DISPLAY 0.680851 (3325 1450);
DISPLAY INVISIBLE (3325 1450);
FORCEADD Q_CAP_DIFFBUS..2
R 2
(3150 1325);
FORCEPROP 1 LAST PART_NUMBER SP_CH4221MEE01
J 2
(3034 1413);
DISPLAY 0.574468 (3034 1413);
PAINT GREEN (3034 1413);
DISPLAY INVISIBLE (3034 1413);
FORCEPROP 2 LAST VALUE DIFF BUS_0.22UF
J 2
(3000 1325);
DISPLAY 0.553191 (3000 1325);
FORCEPROP 1 LAST $LOCATION C697
J 2
(3384 1342);
DISPLAY 0.723404 (3384 1342);
PAINT GREEN (3384 1342);
FORCEPROP 2 LASTPIN (3225 1325) $PN 1
J 0
(3235 1335);
DISPLAY 0.808511 (3235 1335);
FORCEPROP 2 LASTPIN (3075 1325) $PN 2
J 2
(3065 1335);
DISPLAY 0.808511 (3065 1335);
FORCEPROP 2 LAST TOLERANCE 20%
J 2
(3075 1375);
DISPLAY 0.553191 (3075 1375);
DISPLAY INVISIBLE (3075 1375);
FORCEPROP 2 LAST PACK_TYPE C0201
J 2
(2975 1375);
DISPLAY 0.553191 (2975 1375);
DISPLAY INVISIBLE (2975 1375);
FORCEPROP 1 LAST MATERIAL X6S
J 2
(3159 1404);
DISPLAY 0.574468 (3159 1404);
PAINT GREEN (3159 1404);
DISPLAY INVISIBLE (3159 1404);
FORCEPROP 2 LAST VOLTAGE 6.3V
J 2
(2800 1375);
DISPLAY 0.553191 (2800 1375);
DISPLAY INVISIBLE (2800 1375);
FORCEPROP 1 LAST CDS_LMAN_SYM_OUTLINE -25,50,25,-50
J 2
(3150 1325);
DISPLAY 0.468085 (3150 1325);
PAINT GREEN (3150 1325);
DISPLAY INVISIBLE (3150 1325);
FORCEPROP 2 LAST CDS_LIB pure_quanta
J 2
(3150 1325);
DISPLAY INVISIBLE (3150 1325);
FORCEPROP 1 LAST PIN_NAMES_ROTATE TRUE
J 2
(3150 1325);
DISPLAY 0.489362 (3150 1325);
PAINT GREEN (3150 1325);
DISPLAY INVISIBLE (3150 1325);
FORCEPROP 1 LAST PATH I138
J 2
(3150 1325);
DISPLAY 0.723404 (3150 1325);
DISPLAY INVISIBLE (3150 1325);
FORCEPROP 1 LAST $LOCATION C697
J 0
(3400 1400);
DISPLAY 1.021277 (3400 1400);
DISPLAY INVISIBLE (3400 1400);
FORCEPROP 2 LAST CDS_LOCATION C697
J 0
(3400 1400);
DISPLAY 1.021277 (3400 1400);
DISPLAY INVISIBLE (3400 1400);
FORCEPROP 2 LAST $SEC 1
J 2
(3325 1400);
DISPLAY 0.680851 (3325 1400);
PAINT MONO (3325 1400);
DISPLAY INVISIBLE (3325 1400);
FORCEPROP 2 LAST CDS_SEC 1
J 2
(3325 1400);
DISPLAY 0.680851 (3325 1400);
DISPLAY INVISIBLE (3325 1400);
FORCEADD Q_CAP_DIFFBUS..2
R 2
(3150 1525);
FORCEPROP 1 LAST PART_NUMBER SP_CH4221MEE01
J 2
(3034 1613);
DISPLAY 0.574468 (3034 1613);
PAINT GREEN (3034 1613);
DISPLAY INVISIBLE (3034 1613);
FORCEPROP 2 LAST VALUE DIFF BUS_0.22UF
J 2
(3000 1525);
DISPLAY 0.553191 (3000 1525);
FORCEPROP 1 LAST $LOCATION C695
J 2
(3384 1542);
DISPLAY 0.723404 (3384 1542);
PAINT GREEN (3384 1542);
FORCEPROP 2 LASTPIN (3225 1525) $PN 1
J 0
(3235 1535);
DISPLAY 0.808511 (3235 1535);
FORCEPROP 2 LASTPIN (3075 1525) $PN 2
J 2
(3065 1535);
DISPLAY 0.808511 (3065 1535);
FORCEPROP 2 LAST TOLERANCE 20%
J 2
(3075 1575);
DISPLAY 0.553191 (3075 1575);
DISPLAY INVISIBLE (3075 1575);
FORCEPROP 2 LAST PACK_TYPE C0201
J 2
(2975 1575);
DISPLAY 0.553191 (2975 1575);
DISPLAY INVISIBLE (2975 1575);
FORCEPROP 1 LAST MATERIAL X6S
J 2
(3159 1604);
DISPLAY 0.574468 (3159 1604);
PAINT GREEN (3159 1604);
DISPLAY INVISIBLE (3159 1604);
FORCEPROP 2 LAST VOLTAGE 6.3V
J 2
(2800 1575);
DISPLAY 0.553191 (2800 1575);
DISPLAY INVISIBLE (2800 1575);
FORCEPROP 1 LAST CDS_LMAN_SYM_OUTLINE -25,50,25,-50
J 2
(3150 1525);
DISPLAY 0.468085 (3150 1525);
PAINT GREEN (3150 1525);
DISPLAY INVISIBLE (3150 1525);
FORCEPROP 2 LAST CDS_LIB pure_quanta
J 2
(3150 1525);
DISPLAY INVISIBLE (3150 1525);
FORCEPROP 1 LAST PIN_NAMES_ROTATE TRUE
J 2
(3150 1525);
DISPLAY 0.489362 (3150 1525);
PAINT GREEN (3150 1525);
DISPLAY INVISIBLE (3150 1525);
FORCEPROP 1 LAST PATH I139
J 2
(3150 1525);
DISPLAY 0.723404 (3150 1525);
DISPLAY INVISIBLE (3150 1525);
FORCEPROP 1 LAST $LOCATION C695
J 0
(3400 1600);
DISPLAY 1.021277 (3400 1600);
DISPLAY INVISIBLE (3400 1600);
FORCEPROP 2 LAST CDS_LOCATION C695
J 0
(3400 1600);
DISPLAY 1.021277 (3400 1600);
DISPLAY INVISIBLE (3400 1600);
FORCEPROP 2 LAST $SEC 1
J 2
(3325 1600);
DISPLAY 0.680851 (3325 1600);
PAINT MONO (3325 1600);
DISPLAY INVISIBLE (3325 1600);
FORCEPROP 2 LAST CDS_SEC 1
J 2
(3325 1600);
DISPLAY 0.680851 (3325 1600);
DISPLAY INVISIBLE (3325 1600);
FORCEADD Q_CAP_DIFFBUS..2
R 2
(3150 1575);
FORCEPROP 1 LAST PART_NUMBER SP_CH4221MEE01
J 2
(3034 1663);
DISPLAY 0.574468 (3034 1663);
PAINT GREEN (3034 1663);
DISPLAY INVISIBLE (3034 1663);
FORCEPROP 2 LAST VALUE DIFF BUS_0.22UF
J 2
(3000 1575);
DISPLAY 0.553191 (3000 1575);
FORCEPROP 1 LAST $LOCATION C694
J 2
(3384 1592);
DISPLAY 0.723404 (3384 1592);
PAINT GREEN (3384 1592);
FORCEPROP 2 LASTPIN (3225 1575) $PN 1
J 0
(3235 1585);
DISPLAY 0.808511 (3235 1585);
FORCEPROP 2 LASTPIN (3075 1575) $PN 2
J 2
(3065 1585);
DISPLAY 0.808511 (3065 1585);
FORCEPROP 2 LAST TOLERANCE 20%
J 2
(3075 1625);
DISPLAY 0.553191 (3075 1625);
DISPLAY INVISIBLE (3075 1625);
FORCEPROP 2 LAST PACK_TYPE C0201
J 2
(2975 1625);
DISPLAY 0.553191 (2975 1625);
DISPLAY INVISIBLE (2975 1625);
FORCEPROP 1 LAST MATERIAL X6S
J 2
(3159 1654);
DISPLAY 0.574468 (3159 1654);
PAINT GREEN (3159 1654);
DISPLAY INVISIBLE (3159 1654);
FORCEPROP 2 LAST VOLTAGE 6.3V
J 2
(2800 1625);
DISPLAY 0.553191 (2800 1625);
DISPLAY INVISIBLE (2800 1625);
FORCEPROP 2 LAST CDS_LIB pure_quanta
J 2
(3150 1575);
DISPLAY INVISIBLE (3150 1575);
FORCEPROP 1 LAST CDS_LMAN_SYM_OUTLINE -25,50,25,-50
J 2
(3150 1575);
DISPLAY 0.468085 (3150 1575);
PAINT GREEN (3150 1575);
DISPLAY INVISIBLE (3150 1575);
FORCEPROP 1 LAST PIN_NAMES_ROTATE TRUE
J 2
(3150 1575);
DISPLAY 0.489362 (3150 1575);
PAINT GREEN (3150 1575);
DISPLAY INVISIBLE (3150 1575);
FORCEPROP 1 LAST PATH I140
J 2
(3150 1575);
DISPLAY 0.723404 (3150 1575);
DISPLAY INVISIBLE (3150 1575);
FORCEPROP 1 LAST $LOCATION C694
J 0
(3400 1650);
DISPLAY 1.021277 (3400 1650);
DISPLAY INVISIBLE (3400 1650);
FORCEPROP 2 LAST CDS_LOCATION C694
J 0
(3400 1650);
DISPLAY 1.021277 (3400 1650);
DISPLAY INVISIBLE (3400 1650);
FORCEPROP 2 LAST $SEC 1
J 2
(3325 1650);
DISPLAY 0.680851 (3325 1650);
PAINT MONO (3325 1650);
DISPLAY INVISIBLE (3325 1650);
FORCEPROP 2 LAST CDS_SEC 1
J 2
(3325 1650);
DISPLAY 0.680851 (3325 1650);
DISPLAY INVISIBLE (3325 1650);
FORCEADD TAP..1
R 2
(2175 2100);
FORCEPROP 3 LASTPIN (2225 2100) SIG_NAME P5E_CPU1_PE4_TX_DP<8>
J 0
(2235 2110);
DISPLAY 0.659574 (2235 2110);
PAINT MONO (2235 2110);
DISPLAY INVISIBLE (2235 2110);
FORCEPROP 1 LASTPIN (2225 2100) BN 8
J 2
(2237 2108);
DISPLAY 0.680851 (2237 2108);
PAINT GREEN (2237 2108);
FORCEPROP 2 LAST CDS_LIB standard
J 0
(2175 2100);
DISPLAY INVISIBLE (2175 2100);
FORCEPROP 1 LAST BODY_TYPE PLUMBING
J 2
(2175 2150);
DISPLAY 0.872340 (2175 2150);
PAINT GREEN (2175 2150);
DISPLAY INVISIBLE (2175 2150);
FORCEPROP 1 LAST HDL_TAP TRUE
J 2
(1850 1975);
DISPLAY 0.872340 (1850 1975);
DISPLAY INVISIBLE (1850 1975);
FORCEPROP 1 LAST PATH I141
J 2
(2177 2100);
DISPLAY 0.872340 (2177 2100);
PAINT GREEN (2177 2100);
DISPLAY INVISIBLE (2177 2100);
FORCEADD TAP..1
R 2
(2175 2300);
FORCEPROP 3 LASTPIN (2225 2300) SIG_NAME P5E_CPU1_PE4_TX_DP<9>
J 0
(2235 2310);
DISPLAY 0.659574 (2235 2310);
PAINT MONO (2235 2310);
DISPLAY INVISIBLE (2235 2310);
FORCEPROP 1 LASTPIN (2225 2300) BN 9
J 2
(2237 2308);
DISPLAY 0.680851 (2237 2308);
PAINT GREEN (2237 2308);
FORCEPROP 2 LAST CDS_LIB standard
J 0
(2175 2300);
DISPLAY INVISIBLE (2175 2300);
FORCEPROP 1 LAST BODY_TYPE PLUMBING
J 2
(2175 2350);
DISPLAY 0.872340 (2175 2350);
PAINT GREEN (2175 2350);
DISPLAY INVISIBLE (2175 2350);
FORCEPROP 1 LAST HDL_TAP TRUE
J 2
(1850 2175);
DISPLAY 0.872340 (1850 2175);
DISPLAY INVISIBLE (1850 2175);
FORCEPROP 1 LAST PATH I142
J 2
(2177 2300);
DISPLAY 0.872340 (2177 2300);
PAINT GREEN (2177 2300);
DISPLAY INVISIBLE (2177 2300);
FORCEADD TAP..1
R 2
(2425 2150);
FORCEPROP 3 LASTPIN (2475 2150) SIG_NAME P5E_CPU1_PE4_TX_DN<8>
J 0
(2485 2160);
DISPLAY 0.659574 (2485 2160);
PAINT MONO (2485 2160);
DISPLAY INVISIBLE (2485 2160);
FORCEPROP 1 LASTPIN (2475 2150) BN 8
J 2
(2487 2158);
DISPLAY 0.680851 (2487 2158);
PAINT GREEN (2487 2158);
FORCEPROP 2 LAST CDS_LIB standard
J 0
(2425 2150);
DISPLAY INVISIBLE (2425 2150);
FORCEPROP 1 LAST BODY_TYPE PLUMBING
J 2
(2425 2200);
DISPLAY 0.872340 (2425 2200);
PAINT GREEN (2425 2200);
DISPLAY INVISIBLE (2425 2200);
FORCEPROP 1 LAST HDL_TAP TRUE
J 2
(2100 2025);
DISPLAY 0.872340 (2100 2025);
DISPLAY INVISIBLE (2100 2025);
FORCEPROP 1 LAST PATH I143
J 2
(2427 2150);
DISPLAY 0.872340 (2427 2150);
PAINT GREEN (2427 2150);
DISPLAY INVISIBLE (2427 2150);
FORCEADD TAP..1
R 2
(2425 2350);
FORCEPROP 3 LASTPIN (2475 2350) SIG_NAME P5E_CPU1_PE4_TX_DN<9>
J 0
(2485 2360);
DISPLAY 0.659574 (2485 2360);
PAINT MONO (2485 2360);
DISPLAY INVISIBLE (2485 2360);
FORCEPROP 1 LASTPIN (2475 2350) BN 9
J 2
(2487 2358);
DISPLAY 0.680851 (2487 2358);
PAINT GREEN (2487 2358);
FORCEPROP 2 LAST CDS_LIB standard
J 0
(2425 2350);
DISPLAY INVISIBLE (2425 2350);
FORCEPROP 1 LAST BODY_TYPE PLUMBING
J 2
(2425 2400);
DISPLAY 0.872340 (2425 2400);
PAINT GREEN (2425 2400);
DISPLAY INVISIBLE (2425 2400);
FORCEPROP 1 LAST HDL_TAP TRUE
J 2
(2100 2225);
DISPLAY 0.872340 (2100 2225);
DISPLAY INVISIBLE (2100 2225);
FORCEPROP 1 LAST PATH I144
J 2
(2427 2350);
DISPLAY 0.872340 (2427 2350);
PAINT GREEN (2427 2350);
DISPLAY INVISIBLE (2427 2350);
FORCEADD TAP..1
R 2
(2175 2700);
FORCEPROP 3 LASTPIN (2225 2700) SIG_NAME P5E_CPU1_PE4_TX_DP<11>
J 0
(2235 2710);
DISPLAY 0.659574 (2235 2710);
PAINT MONO (2235 2710);
DISPLAY INVISIBLE (2235 2710);
FORCEPROP 1 LASTPIN (2225 2700) BN 11
J 2
(2237 2708);
DISPLAY 0.680851 (2237 2708);
PAINT GREEN (2237 2708);
FORCEPROP 2 LAST CDS_LIB standard
J 0
(2175 2700);
DISPLAY INVISIBLE (2175 2700);
FORCEPROP 1 LAST BODY_TYPE PLUMBING
J 2
(2175 2750);
DISPLAY 0.872340 (2175 2750);
PAINT GREEN (2175 2750);
DISPLAY INVISIBLE (2175 2750);
FORCEPROP 1 LAST HDL_TAP TRUE
J 2
(1850 2575);
DISPLAY 0.872340 (1850 2575);
DISPLAY INVISIBLE (1850 2575);
FORCEPROP 1 LAST PATH I145
J 2
(2177 2700);
DISPLAY 0.872340 (2177 2700);
PAINT GREEN (2177 2700);
DISPLAY INVISIBLE (2177 2700);
FORCEADD TAP..1
R 2
(2175 2500);
FORCEPROP 3 LASTPIN (2225 2500) SIG_NAME P5E_CPU1_PE4_TX_DP<10>
J 0
(2235 2510);
DISPLAY 0.659574 (2235 2510);
PAINT MONO (2235 2510);
DISPLAY INVISIBLE (2235 2510);
FORCEPROP 1 LASTPIN (2225 2500) BN 10
J 2
(2237 2508);
DISPLAY 0.680851 (2237 2508);
PAINT GREEN (2237 2508);
FORCEPROP 2 LAST CDS_LIB standard
J 0
(2175 2500);
DISPLAY INVISIBLE (2175 2500);
FORCEPROP 1 LAST BODY_TYPE PLUMBING
J 2
(2175 2550);
DISPLAY 0.872340 (2175 2550);
PAINT GREEN (2175 2550);
DISPLAY INVISIBLE (2175 2550);
FORCEPROP 1 LAST HDL_TAP TRUE
J 2
(1850 2375);
DISPLAY 0.872340 (1850 2375);
DISPLAY INVISIBLE (1850 2375);
FORCEPROP 1 LAST PATH I146
J 2
(2177 2500);
DISPLAY 0.872340 (2177 2500);
PAINT GREEN (2177 2500);
DISPLAY INVISIBLE (2177 2500);
FORCEADD TAP..1
R 2
(2175 2900);
FORCEPROP 3 LASTPIN (2225 2900) SIG_NAME P5E_CPU1_PE4_TX_DP<12>
J 0
(2235 2910);
DISPLAY 0.659574 (2235 2910);
PAINT MONO (2235 2910);
DISPLAY INVISIBLE (2235 2910);
FORCEPROP 1 LASTPIN (2225 2900) BN 12
J 2
(2237 2908);
DISPLAY 0.680851 (2237 2908);
PAINT GREEN (2237 2908);
FORCEPROP 2 LAST CDS_LIB standard
J 0
(2175 2900);
DISPLAY INVISIBLE (2175 2900);
FORCEPROP 1 LAST BODY_TYPE PLUMBING
J 2
(2175 2950);
DISPLAY 0.872340 (2175 2950);
PAINT GREEN (2175 2950);
DISPLAY INVISIBLE (2175 2950);
FORCEPROP 1 LAST HDL_TAP TRUE
J 2
(1850 2775);
DISPLAY 0.872340 (1850 2775);
DISPLAY INVISIBLE (1850 2775);
FORCEPROP 1 LAST PATH I147
J 2
(2177 2900);
DISPLAY 0.872340 (2177 2900);
PAINT GREEN (2177 2900);
DISPLAY INVISIBLE (2177 2900);
FORCEADD TAP..1
R 2
(2425 2550);
FORCEPROP 3 LASTPIN (2475 2550) SIG_NAME P5E_CPU1_PE4_TX_DN<10>
J 0
(2485 2560);
DISPLAY 0.659574 (2485 2560);
PAINT MONO (2485 2560);
DISPLAY INVISIBLE (2485 2560);
FORCEPROP 1 LASTPIN (2475 2550) BN 10
J 2
(2487 2558);
DISPLAY 0.680851 (2487 2558);
PAINT GREEN (2487 2558);
FORCEPROP 2 LAST CDS_LIB standard
J 0
(2425 2550);
DISPLAY INVISIBLE (2425 2550);
FORCEPROP 1 LAST BODY_TYPE PLUMBING
J 2
(2425 2600);
DISPLAY 0.872340 (2425 2600);
PAINT GREEN (2425 2600);
DISPLAY INVISIBLE (2425 2600);
FORCEPROP 1 LAST HDL_TAP TRUE
J 2
(2100 2425);
DISPLAY 0.872340 (2100 2425);
DISPLAY INVISIBLE (2100 2425);
FORCEPROP 1 LAST PATH I148
J 2
(2427 2550);
DISPLAY 0.872340 (2427 2550);
PAINT GREEN (2427 2550);
DISPLAY INVISIBLE (2427 2550);
FORCEADD TAP..1
R 2
(2425 2750);
FORCEPROP 3 LASTPIN (2475 2750) SIG_NAME P5E_CPU1_PE4_TX_DN<11>
J 0
(2485 2760);
DISPLAY 0.659574 (2485 2760);
PAINT MONO (2485 2760);
DISPLAY INVISIBLE (2485 2760);
FORCEPROP 1 LASTPIN (2475 2750) BN 11
J 2
(2487 2758);
DISPLAY 0.680851 (2487 2758);
PAINT GREEN (2487 2758);
FORCEPROP 2 LAST CDS_LIB standard
J 0
(2425 2750);
DISPLAY INVISIBLE (2425 2750);
FORCEPROP 1 LAST BODY_TYPE PLUMBING
J 2
(2425 2800);
DISPLAY 0.872340 (2425 2800);
PAINT GREEN (2425 2800);
DISPLAY INVISIBLE (2425 2800);
FORCEPROP 1 LAST HDL_TAP TRUE
J 2
(2100 2625);
DISPLAY 0.872340 (2100 2625);
DISPLAY INVISIBLE (2100 2625);
FORCEPROP 1 LAST PATH I149
J 2
(2427 2750);
DISPLAY 0.872340 (2427 2750);
PAINT GREEN (2427 2750);
DISPLAY INVISIBLE (2427 2750);
FORCEADD TAP..1
R 2
(2425 2950);
FORCEPROP 3 LASTPIN (2475 2950) SIG_NAME P5E_CPU1_PE4_TX_DN<12>
J 0
(2485 2960);
DISPLAY 0.659574 (2485 2960);
PAINT MONO (2485 2960);
DISPLAY INVISIBLE (2485 2960);
FORCEPROP 1 LASTPIN (2475 2950) BN 12
J 2
(2487 2958);
DISPLAY 0.680851 (2487 2958);
PAINT GREEN (2487 2958);
FORCEPROP 2 LAST CDS_LIB standard
J 0
(2425 2950);
DISPLAY INVISIBLE (2425 2950);
FORCEPROP 1 LAST BODY_TYPE PLUMBING
J 2
(2425 3000);
DISPLAY 0.872340 (2425 3000);
PAINT GREEN (2425 3000);
DISPLAY INVISIBLE (2425 3000);
FORCEPROP 1 LAST HDL_TAP TRUE
J 2
(2100 2825);
DISPLAY 0.872340 (2100 2825);
DISPLAY INVISIBLE (2100 2825);
FORCEPROP 1 LAST PATH I150
J 2
(2427 2950);
DISPLAY 0.872340 (2427 2950);
PAINT GREEN (2427 2950);
DISPLAY INVISIBLE (2427 2950);
FORCEADD TAP..1
R 2
(2175 3100);
FORCEPROP 3 LASTPIN (2225 3100) SIG_NAME P5E_CPU1_PE4_TX_DP<13>
J 0
(2235 3110);
DISPLAY 0.659574 (2235 3110);
PAINT MONO (2235 3110);
DISPLAY INVISIBLE (2235 3110);
FORCEPROP 1 LASTPIN (2225 3100) BN 13
J 2
(2237 3108);
DISPLAY 0.680851 (2237 3108);
PAINT GREEN (2237 3108);
FORCEPROP 2 LAST CDS_LIB standard
J 0
(2175 3100);
DISPLAY INVISIBLE (2175 3100);
FORCEPROP 1 LAST BODY_TYPE PLUMBING
J 2
(2175 3150);
DISPLAY 0.872340 (2175 3150);
PAINT GREEN (2175 3150);
DISPLAY INVISIBLE (2175 3150);
FORCEPROP 1 LAST HDL_TAP TRUE
J 2
(1850 2975);
DISPLAY 0.872340 (1850 2975);
DISPLAY INVISIBLE (1850 2975);
FORCEPROP 1 LAST PATH I151
J 2
(2177 3100);
DISPLAY 0.872340 (2177 3100);
PAINT GREEN (2177 3100);
DISPLAY INVISIBLE (2177 3100);
FORCEADD TAP..1
R 2
(2175 3500);
FORCEPROP 3 LASTPIN (2225 3500) SIG_NAME P5E_CPU1_PE4_TX_DP<15>
J 0
(2235 3510);
DISPLAY 0.659574 (2235 3510);
PAINT MONO (2235 3510);
DISPLAY INVISIBLE (2235 3510);
FORCEPROP 1 LASTPIN (2225 3500) BN 15
J 2
(2237 3508);
DISPLAY 0.680851 (2237 3508);
PAINT GREEN (2237 3508);
FORCEPROP 2 LAST CDS_LIB standard
J 0
(2175 3500);
DISPLAY INVISIBLE (2175 3500);
FORCEPROP 1 LAST BODY_TYPE PLUMBING
J 2
(2175 3550);
DISPLAY 0.872340 (2175 3550);
PAINT GREEN (2175 3550);
DISPLAY INVISIBLE (2175 3550);
FORCEPROP 1 LAST HDL_TAP TRUE
J 2
(1850 3375);
DISPLAY 0.872340 (1850 3375);
DISPLAY INVISIBLE (1850 3375);
FORCEPROP 1 LAST PATH I152
J 2
(2177 3500);
DISPLAY 0.872340 (2177 3500);
PAINT GREEN (2177 3500);
DISPLAY INVISIBLE (2177 3500);
FORCEADD TAP..1
R 2
(2175 3300);
FORCEPROP 3 LASTPIN (2225 3300) SIG_NAME P5E_CPU1_PE4_TX_DP<14>
J 0
(2235 3310);
DISPLAY 0.659574 (2235 3310);
PAINT MONO (2235 3310);
DISPLAY INVISIBLE (2235 3310);
FORCEPROP 1 LASTPIN (2225 3300) BN 14
J 2
(2237 3308);
DISPLAY 0.680851 (2237 3308);
PAINT GREEN (2237 3308);
FORCEPROP 2 LAST CDS_LIB standard
J 0
(2175 3300);
DISPLAY INVISIBLE (2175 3300);
FORCEPROP 1 LAST BODY_TYPE PLUMBING
J 2
(2175 3350);
DISPLAY 0.872340 (2175 3350);
PAINT GREEN (2175 3350);
DISPLAY INVISIBLE (2175 3350);
FORCEPROP 1 LAST HDL_TAP TRUE
J 2
(1850 3175);
DISPLAY 0.872340 (1850 3175);
DISPLAY INVISIBLE (1850 3175);
FORCEPROP 1 LAST PATH I153
J 2
(2177 3300);
DISPLAY 0.872340 (2177 3300);
PAINT GREEN (2177 3300);
DISPLAY INVISIBLE (2177 3300);
FORCEADD TAP..1
R 2
(2425 3150);
FORCEPROP 3 LASTPIN (2475 3150) SIG_NAME P5E_CPU1_PE4_TX_DN<13>
J 0
(2485 3160);
DISPLAY 0.659574 (2485 3160);
PAINT MONO (2485 3160);
DISPLAY INVISIBLE (2485 3160);
FORCEPROP 1 LASTPIN (2475 3150) BN 13
J 2
(2487 3158);
DISPLAY 0.680851 (2487 3158);
PAINT GREEN (2487 3158);
FORCEPROP 2 LAST CDS_LIB standard
J 0
(2425 3150);
DISPLAY INVISIBLE (2425 3150);
FORCEPROP 1 LAST BODY_TYPE PLUMBING
J 2
(2425 3200);
DISPLAY 0.872340 (2425 3200);
PAINT GREEN (2425 3200);
DISPLAY INVISIBLE (2425 3200);
FORCEPROP 1 LAST HDL_TAP TRUE
J 2
(2100 3025);
DISPLAY 0.872340 (2100 3025);
DISPLAY INVISIBLE (2100 3025);
FORCEPROP 1 LAST PATH I154
J 2
(2427 3150);
DISPLAY 0.872340 (2427 3150);
PAINT GREEN (2427 3150);
DISPLAY INVISIBLE (2427 3150);
FORCEADD TAP..1
R 2
(2425 3350);
FORCEPROP 3 LASTPIN (2475 3350) SIG_NAME P5E_CPU1_PE4_TX_DN<14>
J 0
(2485 3360);
DISPLAY 0.659574 (2485 3360);
PAINT MONO (2485 3360);
DISPLAY INVISIBLE (2485 3360);
FORCEPROP 1 LASTPIN (2475 3350) BN 14
J 2
(2487 3358);
DISPLAY 0.680851 (2487 3358);
PAINT GREEN (2487 3358);
FORCEPROP 2 LAST CDS_LIB standard
J 0
(2425 3350);
DISPLAY INVISIBLE (2425 3350);
FORCEPROP 1 LAST BODY_TYPE PLUMBING
J 2
(2425 3400);
DISPLAY 0.872340 (2425 3400);
PAINT GREEN (2425 3400);
DISPLAY INVISIBLE (2425 3400);
FORCEPROP 1 LAST HDL_TAP TRUE
J 2
(2100 3225);
DISPLAY 0.872340 (2100 3225);
DISPLAY INVISIBLE (2100 3225);
FORCEPROP 1 LAST PATH I155
J 2
(2427 3350);
DISPLAY 0.872340 (2427 3350);
PAINT GREEN (2427 3350);
DISPLAY INVISIBLE (2427 3350);
FORCEADD TAP..1
R 2
(2425 3550);
FORCEPROP 3 LASTPIN (2475 3550) SIG_NAME P5E_CPU1_PE4_TX_DN<15>
J 0
(2485 3560);
DISPLAY 0.659574 (2485 3560);
PAINT MONO (2485 3560);
DISPLAY INVISIBLE (2485 3560);
FORCEPROP 1 LASTPIN (2475 3550) BN 15
J 2
(2487 3558);
DISPLAY 0.680851 (2487 3558);
PAINT GREEN (2487 3558);
FORCEPROP 2 LAST CDS_LIB standard
J 0
(2425 3550);
DISPLAY INVISIBLE (2425 3550);
FORCEPROP 1 LAST BODY_TYPE PLUMBING
J 2
(2425 3600);
DISPLAY 0.872340 (2425 3600);
PAINT GREEN (2425 3600);
DISPLAY INVISIBLE (2425 3600);
FORCEPROP 1 LAST HDL_TAP TRUE
J 2
(2100 3425);
DISPLAY 0.872340 (2100 3425);
DISPLAY INVISIBLE (2100 3425);
FORCEPROP 1 LAST PATH I156
J 2
(2427 3550);
DISPLAY 0.872340 (2427 3550);
PAINT GREEN (2427 3550);
DISPLAY INVISIBLE (2427 3550);
FORCEADD Q_CAP_DIFFBUS..2
R 2
(3150 2100);
FORCEPROP 1 LAST PART_NUMBER SP_CH4221MEE01
J 2
(3034 2188);
DISPLAY 0.574468 (3034 2188);
PAINT GREEN (3034 2188);
DISPLAY INVISIBLE (3034 2188);
FORCEPROP 2 LAST VALUE DIFF BUS_0.22UF
J 2
(3000 2100);
DISPLAY 0.553191 (3000 2100);
FORCEPROP 1 LAST $LOCATION C693
J 2
(3384 2117);
DISPLAY 0.723404 (3384 2117);
PAINT GREEN (3384 2117);
FORCEPROP 2 LASTPIN (3225 2100) $PN 1
J 0
(3235 2110);
DISPLAY 0.808511 (3235 2110);
FORCEPROP 2 LASTPIN (3075 2100) $PN 2
J 2
(3065 2110);
DISPLAY 0.808511 (3065 2110);
FORCEPROP 2 LAST TOLERANCE 20%
J 2
(3075 2150);
DISPLAY 0.553191 (3075 2150);
DISPLAY INVISIBLE (3075 2150);
FORCEPROP 2 LAST PACK_TYPE C0201
J 2
(2975 2150);
DISPLAY 0.553191 (2975 2150);
DISPLAY INVISIBLE (2975 2150);
FORCEPROP 1 LAST MATERIAL X6S
J 2
(3159 2179);
DISPLAY 0.574468 (3159 2179);
PAINT GREEN (3159 2179);
DISPLAY INVISIBLE (3159 2179);
FORCEPROP 2 LAST VOLTAGE 6.3V
J 2
(2800 2150);
DISPLAY 0.553191 (2800 2150);
DISPLAY INVISIBLE (2800 2150);
FORCEPROP 1 LAST PIN_NAMES_ROTATE TRUE
J 2
(3150 2100);
DISPLAY 0.489362 (3150 2100);
PAINT GREEN (3150 2100);
DISPLAY INVISIBLE (3150 2100);
FORCEPROP 2 LAST CDS_LIB pure_quanta
J 2
(3150 2100);
DISPLAY INVISIBLE (3150 2100);
FORCEPROP 1 LAST CDS_LMAN_SYM_OUTLINE -25,50,25,-50
J 2
(3150 2100);
DISPLAY 0.468085 (3150 2100);
PAINT GREEN (3150 2100);
DISPLAY INVISIBLE (3150 2100);
FORCEPROP 1 LAST PATH I157
J 2
(3150 2100);
DISPLAY 0.723404 (3150 2100);
DISPLAY INVISIBLE (3150 2100);
FORCEPROP 1 LAST $LOCATION C693
J 0
(3400 2175);
DISPLAY 1.021277 (3400 2175);
DISPLAY INVISIBLE (3400 2175);
FORCEPROP 2 LAST CDS_LOCATION C693
J 0
(3400 2175);
DISPLAY 1.021277 (3400 2175);
DISPLAY INVISIBLE (3400 2175);
FORCEPROP 2 LAST $SEC 1
J 2
(3325 2175);
DISPLAY 0.680851 (3325 2175);
PAINT MONO (3325 2175);
DISPLAY INVISIBLE (3325 2175);
FORCEPROP 2 LAST CDS_SEC 1
J 2
(3325 2175);
DISPLAY 0.680851 (3325 2175);
DISPLAY INVISIBLE (3325 2175);
FORCEADD Q_CAP_DIFFBUS..2
R 2
(3150 2150);
FORCEPROP 1 LAST PART_NUMBER SP_CH4221MEE01
J 2
(3034 2238);
DISPLAY 0.574468 (3034 2238);
PAINT GREEN (3034 2238);
DISPLAY INVISIBLE (3034 2238);
FORCEPROP 2 LAST VALUE DIFF BUS_0.22UF
J 2
(3000 2150);
DISPLAY 0.553191 (3000 2150);
FORCEPROP 1 LAST $LOCATION C692
J 2
(3384 2167);
DISPLAY 0.723404 (3384 2167);
PAINT GREEN (3384 2167);
FORCEPROP 2 LASTPIN (3225 2150) $PN 1
J 0
(3235 2160);
DISPLAY 0.808511 (3235 2160);
FORCEPROP 2 LASTPIN (3075 2150) $PN 2
J 2
(3065 2160);
DISPLAY 0.808511 (3065 2160);
FORCEPROP 2 LAST TOLERANCE 20%
J 2
(3075 2200);
DISPLAY 0.553191 (3075 2200);
DISPLAY INVISIBLE (3075 2200);
FORCEPROP 2 LAST PACK_TYPE C0201
J 2
(2975 2200);
DISPLAY 0.553191 (2975 2200);
DISPLAY INVISIBLE (2975 2200);
FORCEPROP 1 LAST MATERIAL X6S
J 2
(3159 2229);
DISPLAY 0.574468 (3159 2229);
PAINT GREEN (3159 2229);
DISPLAY INVISIBLE (3159 2229);
FORCEPROP 2 LAST VOLTAGE 6.3V
J 2
(2800 2200);
DISPLAY 0.553191 (2800 2200);
DISPLAY INVISIBLE (2800 2200);
FORCEPROP 1 LAST PIN_NAMES_ROTATE TRUE
J 2
(3150 2150);
DISPLAY 0.489362 (3150 2150);
PAINT GREEN (3150 2150);
DISPLAY INVISIBLE (3150 2150);
FORCEPROP 2 LAST CDS_LIB pure_quanta
J 2
(3150 2150);
DISPLAY INVISIBLE (3150 2150);
FORCEPROP 1 LAST CDS_LMAN_SYM_OUTLINE -25,50,25,-50
J 2
(3150 2150);
DISPLAY 0.468085 (3150 2150);
PAINT GREEN (3150 2150);
DISPLAY INVISIBLE (3150 2150);
FORCEPROP 1 LAST PATH I158
J 2
(3150 2150);
DISPLAY 0.723404 (3150 2150);
DISPLAY INVISIBLE (3150 2150);
FORCEPROP 1 LAST $LOCATION C692
J 0
(3400 2225);
DISPLAY 1.021277 (3400 2225);
DISPLAY INVISIBLE (3400 2225);
FORCEPROP 2 LAST CDS_LOCATION C692
J 0
(3400 2225);
DISPLAY 1.021277 (3400 2225);
DISPLAY INVISIBLE (3400 2225);
FORCEPROP 2 LAST $SEC 1
J 2
(3325 2225);
DISPLAY 0.680851 (3325 2225);
PAINT MONO (3325 2225);
DISPLAY INVISIBLE (3325 2225);
FORCEPROP 2 LAST CDS_SEC 1
J 2
(3325 2225);
DISPLAY 0.680851 (3325 2225);
DISPLAY INVISIBLE (3325 2225);
FORCEADD Q_CAP_DIFFBUS..2
R 2
(3150 2350);
FORCEPROP 1 LAST PART_NUMBER SP_CH4221MEE01
J 2
(3034 2438);
DISPLAY 0.574468 (3034 2438);
PAINT GREEN (3034 2438);
DISPLAY INVISIBLE (3034 2438);
FORCEPROP 2 LAST VALUE DIFF BUS_0.22UF
J 2
(3000 2350);
DISPLAY 0.553191 (3000 2350);
FORCEPROP 1 LAST $LOCATION C690
J 2
(3384 2367);
DISPLAY 0.723404 (3384 2367);
PAINT GREEN (3384 2367);
FORCEPROP 2 LASTPIN (3225 2350) $PN 1
J 0
(3235 2360);
DISPLAY 0.808511 (3235 2360);
FORCEPROP 2 LASTPIN (3075 2350) $PN 2
J 2
(3065 2360);
DISPLAY 0.808511 (3065 2360);
FORCEPROP 2 LAST TOLERANCE 20%
J 2
(3075 2400);
DISPLAY 0.553191 (3075 2400);
DISPLAY INVISIBLE (3075 2400);
FORCEPROP 2 LAST PACK_TYPE C0201
J 2
(2975 2400);
DISPLAY 0.553191 (2975 2400);
DISPLAY INVISIBLE (2975 2400);
FORCEPROP 1 LAST MATERIAL X6S
J 2
(3159 2429);
DISPLAY 0.574468 (3159 2429);
PAINT GREEN (3159 2429);
DISPLAY INVISIBLE (3159 2429);
FORCEPROP 2 LAST VOLTAGE 6.3V
J 2
(2800 2400);
DISPLAY 0.553191 (2800 2400);
DISPLAY INVISIBLE (2800 2400);
FORCEPROP 1 LAST PIN_NAMES_ROTATE TRUE
J 2
(3150 2350);
DISPLAY 0.489362 (3150 2350);
PAINT GREEN (3150 2350);
DISPLAY INVISIBLE (3150 2350);
FORCEPROP 1 LAST CDS_LMAN_SYM_OUTLINE -25,50,25,-50
J 2
(3150 2350);
DISPLAY 0.468085 (3150 2350);
PAINT GREEN (3150 2350);
DISPLAY INVISIBLE (3150 2350);
FORCEPROP 2 LAST CDS_LIB pure_quanta
J 2
(3150 2350);
DISPLAY INVISIBLE (3150 2350);
FORCEPROP 1 LAST PATH I159
J 2
(3150 2350);
DISPLAY 0.723404 (3150 2350);
DISPLAY INVISIBLE (3150 2350);
FORCEPROP 1 LAST $LOCATION C690
J 0
(3400 2425);
DISPLAY 1.021277 (3400 2425);
DISPLAY INVISIBLE (3400 2425);
FORCEPROP 2 LAST CDS_LOCATION C690
J 0
(3400 2425);
DISPLAY 1.021277 (3400 2425);
DISPLAY INVISIBLE (3400 2425);
FORCEPROP 2 LAST $SEC 1
J 2
(3325 2425);
DISPLAY 0.680851 (3325 2425);
PAINT MONO (3325 2425);
DISPLAY INVISIBLE (3325 2425);
FORCEPROP 2 LAST CDS_SEC 1
J 2
(3325 2425);
DISPLAY 0.680851 (3325 2425);
DISPLAY INVISIBLE (3325 2425);
FORCEADD Q_CAP_DIFFBUS..2
R 2
(3150 2300);
FORCEPROP 1 LAST PART_NUMBER SP_CH4221MEE01
J 2
(3034 2388);
DISPLAY 0.574468 (3034 2388);
PAINT GREEN (3034 2388);
DISPLAY INVISIBLE (3034 2388);
FORCEPROP 2 LAST VALUE DIFF BUS_0.22UF
J 2
(3000 2300);
DISPLAY 0.553191 (3000 2300);
FORCEPROP 1 LAST $LOCATION C691
J 2
(3384 2317);
DISPLAY 0.723404 (3384 2317);
PAINT GREEN (3384 2317);
FORCEPROP 2 LASTPIN (3225 2300) $PN 1
J 0
(3235 2310);
DISPLAY 0.808511 (3235 2310);
FORCEPROP 2 LASTPIN (3075 2300) $PN 2
J 2
(3065 2310);
DISPLAY 0.808511 (3065 2310);
FORCEPROP 2 LAST TOLERANCE 20%
J 2
(3075 2350);
DISPLAY 0.553191 (3075 2350);
DISPLAY INVISIBLE (3075 2350);
FORCEPROP 2 LAST PACK_TYPE C0201
J 2
(2975 2350);
DISPLAY 0.553191 (2975 2350);
DISPLAY INVISIBLE (2975 2350);
FORCEPROP 1 LAST MATERIAL X6S
J 2
(3159 2379);
DISPLAY 0.574468 (3159 2379);
PAINT GREEN (3159 2379);
DISPLAY INVISIBLE (3159 2379);
FORCEPROP 2 LAST VOLTAGE 6.3V
J 2
(2800 2350);
DISPLAY 0.553191 (2800 2350);
DISPLAY INVISIBLE (2800 2350);
FORCEPROP 1 LAST PIN_NAMES_ROTATE TRUE
J 2
(3150 2300);
DISPLAY 0.489362 (3150 2300);
PAINT GREEN (3150 2300);
DISPLAY INVISIBLE (3150 2300);
FORCEPROP 2 LAST CDS_LIB pure_quanta
J 2
(3150 2300);
DISPLAY INVISIBLE (3150 2300);
FORCEPROP 1 LAST CDS_LMAN_SYM_OUTLINE -25,50,25,-50
J 2
(3150 2300);
DISPLAY 0.468085 (3150 2300);
PAINT GREEN (3150 2300);
DISPLAY INVISIBLE (3150 2300);
FORCEPROP 1 LAST PATH I160
J 2
(3150 2300);
DISPLAY 0.723404 (3150 2300);
DISPLAY INVISIBLE (3150 2300);
FORCEPROP 1 LAST $LOCATION C691
J 0
(3400 2375);
DISPLAY 1.021277 (3400 2375);
DISPLAY INVISIBLE (3400 2375);
FORCEPROP 2 LAST CDS_LOCATION C691
J 0
(3400 2375);
DISPLAY 1.021277 (3400 2375);
DISPLAY INVISIBLE (3400 2375);
FORCEPROP 2 LAST $SEC 1
J 2
(3325 2375);
DISPLAY 0.680851 (3325 2375);
PAINT MONO (3325 2375);
DISPLAY INVISIBLE (3325 2375);
FORCEPROP 2 LAST CDS_SEC 1
J 2
(3325 2375);
DISPLAY 0.680851 (3325 2375);
DISPLAY INVISIBLE (3325 2375);
FORCEADD Q_CAP_DIFFBUS..2
R 2
(3150 2700);
FORCEPROP 1 LAST PART_NUMBER SP_CH4221MEE01
J 2
(3034 2788);
DISPLAY 0.574468 (3034 2788);
PAINT GREEN (3034 2788);
DISPLAY INVISIBLE (3034 2788);
FORCEPROP 2 LAST VALUE DIFF BUS_0.22UF
J 2
(3000 2700);
DISPLAY 0.553191 (3000 2700);
FORCEPROP 1 LAST $LOCATION C687
J 2
(3384 2717);
DISPLAY 0.723404 (3384 2717);
PAINT GREEN (3384 2717);
FORCEPROP 2 LASTPIN (3225 2700) $PN 1
J 0
(3235 2710);
DISPLAY 0.808511 (3235 2710);
FORCEPROP 2 LASTPIN (3075 2700) $PN 2
J 2
(3065 2710);
DISPLAY 0.808511 (3065 2710);
FORCEPROP 2 LAST TOLERANCE 20%
J 2
(3075 2750);
DISPLAY 0.553191 (3075 2750);
DISPLAY INVISIBLE (3075 2750);
FORCEPROP 2 LAST PACK_TYPE C0201
J 2
(2975 2750);
DISPLAY 0.553191 (2975 2750);
DISPLAY INVISIBLE (2975 2750);
FORCEPROP 1 LAST MATERIAL X6S
J 2
(3159 2779);
DISPLAY 0.574468 (3159 2779);
PAINT GREEN (3159 2779);
DISPLAY INVISIBLE (3159 2779);
FORCEPROP 2 LAST VOLTAGE 6.3V
J 2
(2800 2750);
DISPLAY 0.553191 (2800 2750);
DISPLAY INVISIBLE (2800 2750);
FORCEPROP 1 LAST PIN_NAMES_ROTATE TRUE
J 2
(3150 2700);
DISPLAY 0.489362 (3150 2700);
PAINT GREEN (3150 2700);
DISPLAY INVISIBLE (3150 2700);
FORCEPROP 1 LAST CDS_LMAN_SYM_OUTLINE -25,50,25,-50
J 2
(3150 2700);
DISPLAY 0.468085 (3150 2700);
PAINT GREEN (3150 2700);
DISPLAY INVISIBLE (3150 2700);
FORCEPROP 2 LAST CDS_LIB pure_quanta
J 2
(3150 2700);
DISPLAY INVISIBLE (3150 2700);
FORCEPROP 1 LAST PATH I161
J 2
(3150 2700);
DISPLAY 0.723404 (3150 2700);
DISPLAY INVISIBLE (3150 2700);
FORCEPROP 1 LAST $LOCATION C687
J 0
(3400 2775);
DISPLAY 1.021277 (3400 2775);
DISPLAY INVISIBLE (3400 2775);
FORCEPROP 2 LAST CDS_LOCATION C687
J 0
(3400 2775);
DISPLAY 1.021277 (3400 2775);
DISPLAY INVISIBLE (3400 2775);
FORCEPROP 2 LAST $SEC 1
J 2
(3325 2775);
DISPLAY 0.680851 (3325 2775);
PAINT MONO (3325 2775);
DISPLAY INVISIBLE (3325 2775);
FORCEPROP 2 LAST CDS_SEC 1
J 2
(3325 2775);
DISPLAY 0.680851 (3325 2775);
DISPLAY INVISIBLE (3325 2775);
FORCEADD Q_CAP_DIFFBUS..2
R 2
(3150 2550);
FORCEPROP 1 LAST PART_NUMBER SP_CH4221MEE01
J 2
(3034 2638);
DISPLAY 0.574468 (3034 2638);
PAINT GREEN (3034 2638);
DISPLAY INVISIBLE (3034 2638);
FORCEPROP 2 LAST VALUE DIFF BUS_0.22UF
J 2
(3000 2550);
DISPLAY 0.553191 (3000 2550);
FORCEPROP 1 LAST $LOCATION C688
J 2
(3384 2567);
DISPLAY 0.723404 (3384 2567);
PAINT GREEN (3384 2567);
FORCEPROP 2 LASTPIN (3225 2550) $PN 1
J 0
(3235 2560);
DISPLAY 0.808511 (3235 2560);
FORCEPROP 2 LASTPIN (3075 2550) $PN 2
J 2
(3065 2560);
DISPLAY 0.808511 (3065 2560);
FORCEPROP 2 LAST TOLERANCE 20%
J 2
(3075 2600);
DISPLAY 0.553191 (3075 2600);
DISPLAY INVISIBLE (3075 2600);
FORCEPROP 2 LAST PACK_TYPE C0201
J 2
(2975 2600);
DISPLAY 0.553191 (2975 2600);
DISPLAY INVISIBLE (2975 2600);
FORCEPROP 1 LAST MATERIAL X6S
J 2
(3159 2629);
DISPLAY 0.574468 (3159 2629);
PAINT GREEN (3159 2629);
DISPLAY INVISIBLE (3159 2629);
FORCEPROP 2 LAST VOLTAGE 6.3V
J 2
(2800 2600);
DISPLAY 0.553191 (2800 2600);
DISPLAY INVISIBLE (2800 2600);
FORCEPROP 1 LAST PIN_NAMES_ROTATE TRUE
J 2
(3150 2550);
DISPLAY 0.489362 (3150 2550);
PAINT GREEN (3150 2550);
DISPLAY INVISIBLE (3150 2550);
FORCEPROP 2 LAST CDS_LIB pure_quanta
J 2
(3150 2550);
DISPLAY INVISIBLE (3150 2550);
FORCEPROP 1 LAST CDS_LMAN_SYM_OUTLINE -25,50,25,-50
J 2
(3150 2550);
DISPLAY 0.468085 (3150 2550);
PAINT GREEN (3150 2550);
DISPLAY INVISIBLE (3150 2550);
FORCEPROP 1 LAST PATH I162
J 2
(3150 2550);
DISPLAY 0.723404 (3150 2550);
DISPLAY INVISIBLE (3150 2550);
FORCEPROP 1 LAST $LOCATION C688
J 0
(3400 2625);
DISPLAY 1.021277 (3400 2625);
DISPLAY INVISIBLE (3400 2625);
FORCEPROP 2 LAST CDS_LOCATION C688
J 0
(3400 2625);
DISPLAY 1.021277 (3400 2625);
DISPLAY INVISIBLE (3400 2625);
FORCEPROP 2 LAST $SEC 1
J 2
(3325 2625);
DISPLAY 0.680851 (3325 2625);
PAINT MONO (3325 2625);
DISPLAY INVISIBLE (3325 2625);
FORCEPROP 2 LAST CDS_SEC 1
J 2
(3325 2625);
DISPLAY 0.680851 (3325 2625);
DISPLAY INVISIBLE (3325 2625);
FORCEADD Q_CAP_DIFFBUS..2
R 2
(3150 2500);
FORCEPROP 1 LAST PART_NUMBER SP_CH4221MEE01
J 2
(3034 2588);
DISPLAY 0.574468 (3034 2588);
PAINT GREEN (3034 2588);
DISPLAY INVISIBLE (3034 2588);
FORCEPROP 2 LAST VALUE DIFF BUS_0.22UF
J 2
(3000 2500);
DISPLAY 0.553191 (3000 2500);
FORCEPROP 1 LAST $LOCATION C689
J 2
(3384 2517);
DISPLAY 0.723404 (3384 2517);
PAINT GREEN (3384 2517);
FORCEPROP 2 LASTPIN (3225 2500) $PN 1
J 0
(3235 2510);
DISPLAY 0.808511 (3235 2510);
FORCEPROP 2 LASTPIN (3075 2500) $PN 2
J 2
(3065 2510);
DISPLAY 0.808511 (3065 2510);
FORCEPROP 2 LAST TOLERANCE 20%
J 2
(3075 2550);
DISPLAY 0.553191 (3075 2550);
DISPLAY INVISIBLE (3075 2550);
FORCEPROP 2 LAST PACK_TYPE C0201
J 2
(2975 2550);
DISPLAY 0.553191 (2975 2550);
DISPLAY INVISIBLE (2975 2550);
FORCEPROP 1 LAST MATERIAL X6S
J 2
(3159 2579);
DISPLAY 0.574468 (3159 2579);
PAINT GREEN (3159 2579);
DISPLAY INVISIBLE (3159 2579);
FORCEPROP 2 LAST VOLTAGE 6.3V
J 2
(2800 2550);
DISPLAY 0.553191 (2800 2550);
DISPLAY INVISIBLE (2800 2550);
FORCEPROP 1 LAST PIN_NAMES_ROTATE TRUE
J 2
(3150 2500);
DISPLAY 0.489362 (3150 2500);
PAINT GREEN (3150 2500);
DISPLAY INVISIBLE (3150 2500);
FORCEPROP 2 LAST CDS_LIB pure_quanta
J 2
(3150 2500);
DISPLAY INVISIBLE (3150 2500);
FORCEPROP 1 LAST CDS_LMAN_SYM_OUTLINE -25,50,25,-50
J 2
(3150 2500);
DISPLAY 0.468085 (3150 2500);
PAINT GREEN (3150 2500);
DISPLAY INVISIBLE (3150 2500);
FORCEPROP 1 LAST PATH I163
J 2
(3150 2500);
DISPLAY 0.723404 (3150 2500);
DISPLAY INVISIBLE (3150 2500);
FORCEPROP 1 LAST $LOCATION C689
J 0
(3400 2575);
DISPLAY 1.021277 (3400 2575);
DISPLAY INVISIBLE (3400 2575);
FORCEPROP 2 LAST CDS_LOCATION C689
J 0
(3400 2575);
DISPLAY 1.021277 (3400 2575);
DISPLAY INVISIBLE (3400 2575);
FORCEPROP 2 LAST $SEC 1
J 2
(3325 2575);
DISPLAY 0.680851 (3325 2575);
PAINT MONO (3325 2575);
DISPLAY INVISIBLE (3325 2575);
FORCEPROP 2 LAST CDS_SEC 1
J 2
(3325 2575);
DISPLAY 0.680851 (3325 2575);
DISPLAY INVISIBLE (3325 2575);
FORCEADD Q_CAP_DIFFBUS..2
R 2
(3150 2750);
FORCEPROP 1 LAST PART_NUMBER SP_CH4221MEE01
J 2
(3034 2838);
DISPLAY 0.574468 (3034 2838);
PAINT GREEN (3034 2838);
DISPLAY INVISIBLE (3034 2838);
FORCEPROP 2 LAST VALUE DIFF BUS_0.22UF
J 2
(3000 2750);
DISPLAY 0.553191 (3000 2750);
FORCEPROP 1 LAST $LOCATION C686
J 2
(3384 2767);
DISPLAY 0.723404 (3384 2767);
PAINT GREEN (3384 2767);
FORCEPROP 2 LASTPIN (3225 2750) $PN 1
J 0
(3235 2760);
DISPLAY 0.808511 (3235 2760);
FORCEPROP 2 LASTPIN (3075 2750) $PN 2
J 2
(3065 2760);
DISPLAY 0.808511 (3065 2760);
FORCEPROP 2 LAST TOLERANCE 20%
J 2
(3075 2800);
DISPLAY 0.553191 (3075 2800);
DISPLAY INVISIBLE (3075 2800);
FORCEPROP 2 LAST PACK_TYPE C0201
J 2
(2975 2800);
DISPLAY 0.553191 (2975 2800);
DISPLAY INVISIBLE (2975 2800);
FORCEPROP 1 LAST MATERIAL X6S
J 2
(3159 2829);
DISPLAY 0.574468 (3159 2829);
PAINT GREEN (3159 2829);
DISPLAY INVISIBLE (3159 2829);
FORCEPROP 2 LAST VOLTAGE 6.3V
J 2
(2800 2800);
DISPLAY 0.553191 (2800 2800);
DISPLAY INVISIBLE (2800 2800);
FORCEPROP 1 LAST PIN_NAMES_ROTATE TRUE
J 2
(3150 2750);
DISPLAY 0.489362 (3150 2750);
PAINT GREEN (3150 2750);
DISPLAY INVISIBLE (3150 2750);
FORCEPROP 1 LAST CDS_LMAN_SYM_OUTLINE -25,50,25,-50
J 2
(3150 2750);
DISPLAY 0.468085 (3150 2750);
PAINT GREEN (3150 2750);
DISPLAY INVISIBLE (3150 2750);
FORCEPROP 2 LAST CDS_LIB pure_quanta
J 2
(3150 2750);
DISPLAY INVISIBLE (3150 2750);
FORCEPROP 1 LAST PATH I164
J 2
(3150 2750);
DISPLAY 0.723404 (3150 2750);
DISPLAY INVISIBLE (3150 2750);
FORCEPROP 1 LAST $LOCATION C686
J 0
(3400 2825);
DISPLAY 1.021277 (3400 2825);
DISPLAY INVISIBLE (3400 2825);
FORCEPROP 2 LAST CDS_LOCATION C686
J 0
(3400 2825);
DISPLAY 1.021277 (3400 2825);
DISPLAY INVISIBLE (3400 2825);
FORCEPROP 2 LAST $SEC 1
J 2
(3325 2825);
DISPLAY 0.680851 (3325 2825);
PAINT MONO (3325 2825);
DISPLAY INVISIBLE (3325 2825);
FORCEPROP 2 LAST CDS_SEC 1
J 2
(3325 2825);
DISPLAY 0.680851 (3325 2825);
DISPLAY INVISIBLE (3325 2825);
FORCEADD Q_CAP_DIFFBUS..2
R 2
(3150 2900);
FORCEPROP 1 LAST PART_NUMBER SP_CH4221MEE01
J 2
(3034 2988);
DISPLAY 0.574468 (3034 2988);
PAINT GREEN (3034 2988);
DISPLAY INVISIBLE (3034 2988);
FORCEPROP 2 LAST VALUE DIFF BUS_0.22UF
J 2
(3000 2900);
DISPLAY 0.553191 (3000 2900);
FORCEPROP 1 LAST $LOCATION C685
J 2
(3384 2917);
DISPLAY 0.723404 (3384 2917);
PAINT GREEN (3384 2917);
FORCEPROP 2 LASTPIN (3225 2900) $PN 1
J 0
(3235 2910);
DISPLAY 0.808511 (3235 2910);
FORCEPROP 2 LASTPIN (3075 2900) $PN 2
J 2
(3065 2910);
DISPLAY 0.808511 (3065 2910);
FORCEPROP 2 LAST TOLERANCE 20%
J 2
(3075 2950);
DISPLAY 0.553191 (3075 2950);
DISPLAY INVISIBLE (3075 2950);
FORCEPROP 2 LAST PACK_TYPE C0201
J 2
(2975 2950);
DISPLAY 0.553191 (2975 2950);
DISPLAY INVISIBLE (2975 2950);
FORCEPROP 1 LAST MATERIAL X6S
J 2
(3159 2979);
DISPLAY 0.574468 (3159 2979);
PAINT GREEN (3159 2979);
DISPLAY INVISIBLE (3159 2979);
FORCEPROP 2 LAST VOLTAGE 6.3V
J 2
(2800 2950);
DISPLAY 0.553191 (2800 2950);
DISPLAY INVISIBLE (2800 2950);
FORCEPROP 1 LAST PIN_NAMES_ROTATE TRUE
J 2
(3150 2900);
DISPLAY 0.489362 (3150 2900);
PAINT GREEN (3150 2900);
DISPLAY INVISIBLE (3150 2900);
FORCEPROP 2 LAST CDS_LIB pure_quanta
J 2
(3150 2900);
DISPLAY INVISIBLE (3150 2900);
FORCEPROP 1 LAST CDS_LMAN_SYM_OUTLINE -25,50,25,-50
J 2
(3150 2900);
DISPLAY 0.468085 (3150 2900);
PAINT GREEN (3150 2900);
DISPLAY INVISIBLE (3150 2900);
FORCEPROP 1 LAST PATH I165
J 2
(3150 2900);
DISPLAY 0.723404 (3150 2900);
DISPLAY INVISIBLE (3150 2900);
FORCEPROP 1 LAST $LOCATION C685
J 0
(3400 2975);
DISPLAY 1.021277 (3400 2975);
DISPLAY INVISIBLE (3400 2975);
FORCEPROP 2 LAST CDS_LOCATION C685
J 0
(3400 2975);
DISPLAY 1.021277 (3400 2975);
DISPLAY INVISIBLE (3400 2975);
FORCEPROP 2 LAST $SEC 1
J 2
(3325 2975);
DISPLAY 0.680851 (3325 2975);
PAINT MONO (3325 2975);
DISPLAY INVISIBLE (3325 2975);
FORCEPROP 2 LAST CDS_SEC 1
J 2
(3325 2975);
DISPLAY 0.680851 (3325 2975);
DISPLAY INVISIBLE (3325 2975);
FORCEADD Q_CAP_DIFFBUS..2
R 2
(3150 2950);
FORCEPROP 1 LAST PART_NUMBER SP_CH4221MEE01
J 2
(3034 3038);
DISPLAY 0.574468 (3034 3038);
PAINT GREEN (3034 3038);
DISPLAY INVISIBLE (3034 3038);
FORCEPROP 2 LAST VALUE DIFF BUS_0.22UF
J 2
(3000 2950);
DISPLAY 0.553191 (3000 2950);
FORCEPROP 1 LAST $LOCATION C684
J 2
(3384 2967);
DISPLAY 0.723404 (3384 2967);
PAINT GREEN (3384 2967);
FORCEPROP 2 LASTPIN (3225 2950) $PN 1
J 0
(3235 2960);
DISPLAY 0.808511 (3235 2960);
FORCEPROP 2 LASTPIN (3075 2950) $PN 2
J 2
(3065 2960);
DISPLAY 0.808511 (3065 2960);
FORCEPROP 2 LAST TOLERANCE 20%
J 2
(3075 3000);
DISPLAY 0.553191 (3075 3000);
DISPLAY INVISIBLE (3075 3000);
FORCEPROP 2 LAST PACK_TYPE C0201
J 2
(2975 3000);
DISPLAY 0.553191 (2975 3000);
DISPLAY INVISIBLE (2975 3000);
FORCEPROP 1 LAST MATERIAL X6S
J 2
(3159 3029);
DISPLAY 0.574468 (3159 3029);
PAINT GREEN (3159 3029);
DISPLAY INVISIBLE (3159 3029);
FORCEPROP 2 LAST VOLTAGE 6.3V
J 2
(2800 3000);
DISPLAY 0.553191 (2800 3000);
DISPLAY INVISIBLE (2800 3000);
FORCEPROP 1 LAST PIN_NAMES_ROTATE TRUE
J 2
(3150 2950);
DISPLAY 0.489362 (3150 2950);
PAINT GREEN (3150 2950);
DISPLAY INVISIBLE (3150 2950);
FORCEPROP 2 LAST CDS_LIB pure_quanta
J 2
(3150 2950);
DISPLAY INVISIBLE (3150 2950);
FORCEPROP 1 LAST CDS_LMAN_SYM_OUTLINE -25,50,25,-50
J 2
(3150 2950);
DISPLAY 0.468085 (3150 2950);
PAINT GREEN (3150 2950);
DISPLAY INVISIBLE (3150 2950);
FORCEPROP 1 LAST PATH I166
J 2
(3150 2950);
DISPLAY 0.723404 (3150 2950);
DISPLAY INVISIBLE (3150 2950);
FORCEPROP 1 LAST $LOCATION C684
J 0
(3400 3025);
DISPLAY 1.021277 (3400 3025);
DISPLAY INVISIBLE (3400 3025);
FORCEPROP 2 LAST CDS_LOCATION C684
J 0
(3400 3025);
DISPLAY 1.021277 (3400 3025);
DISPLAY INVISIBLE (3400 3025);
FORCEPROP 2 LAST $SEC 1
J 2
(3325 3025);
DISPLAY 0.680851 (3325 3025);
PAINT MONO (3325 3025);
DISPLAY INVISIBLE (3325 3025);
FORCEPROP 2 LAST CDS_SEC 1
J 2
(3325 3025);
DISPLAY 0.680851 (3325 3025);
DISPLAY INVISIBLE (3325 3025);
FORCEADD Q_CAP_DIFFBUS..2
R 2
(3150 3150);
FORCEPROP 1 LAST PART_NUMBER SP_CH4221MEE01
J 2
(3034 3238);
DISPLAY 0.574468 (3034 3238);
PAINT GREEN (3034 3238);
DISPLAY INVISIBLE (3034 3238);
FORCEPROP 2 LAST VALUE DIFF BUS_0.22UF
J 2
(3000 3150);
DISPLAY 0.553191 (3000 3150);
FORCEPROP 1 LAST $LOCATION C682
J 2
(3384 3167);
DISPLAY 0.723404 (3384 3167);
PAINT GREEN (3384 3167);
FORCEPROP 2 LASTPIN (3225 3150) $PN 1
J 0
(3235 3160);
DISPLAY 0.808511 (3235 3160);
FORCEPROP 2 LASTPIN (3075 3150) $PN 2
J 2
(3065 3160);
DISPLAY 0.808511 (3065 3160);
FORCEPROP 2 LAST TOLERANCE 20%
J 2
(3075 3200);
DISPLAY 0.553191 (3075 3200);
DISPLAY INVISIBLE (3075 3200);
FORCEPROP 2 LAST PACK_TYPE C0201
J 2
(2975 3200);
DISPLAY 0.553191 (2975 3200);
DISPLAY INVISIBLE (2975 3200);
FORCEPROP 1 LAST MATERIAL X6S
J 2
(3159 3229);
DISPLAY 0.574468 (3159 3229);
PAINT GREEN (3159 3229);
DISPLAY INVISIBLE (3159 3229);
FORCEPROP 2 LAST VOLTAGE 6.3V
J 2
(2800 3200);
DISPLAY 0.553191 (2800 3200);
DISPLAY INVISIBLE (2800 3200);
FORCEPROP 1 LAST PIN_NAMES_ROTATE TRUE
J 2
(3150 3150);
DISPLAY 0.489362 (3150 3150);
PAINT GREEN (3150 3150);
DISPLAY INVISIBLE (3150 3150);
FORCEPROP 2 LAST CDS_LIB pure_quanta
J 2
(3150 3150);
DISPLAY INVISIBLE (3150 3150);
FORCEPROP 1 LAST CDS_LMAN_SYM_OUTLINE -25,50,25,-50
J 2
(3150 3150);
DISPLAY 0.468085 (3150 3150);
PAINT GREEN (3150 3150);
DISPLAY INVISIBLE (3150 3150);
FORCEPROP 1 LAST PATH I167
J 2
(3150 3150);
DISPLAY 0.723404 (3150 3150);
DISPLAY INVISIBLE (3150 3150);
FORCEPROP 1 LAST $LOCATION C682
J 0
(3400 3225);
DISPLAY 1.021277 (3400 3225);
DISPLAY INVISIBLE (3400 3225);
FORCEPROP 2 LAST CDS_LOCATION C682
J 0
(3400 3225);
DISPLAY 1.021277 (3400 3225);
DISPLAY INVISIBLE (3400 3225);
FORCEPROP 2 LAST $SEC 1
J 2
(3325 3225);
DISPLAY 0.680851 (3325 3225);
PAINT MONO (3325 3225);
DISPLAY INVISIBLE (3325 3225);
FORCEPROP 2 LAST CDS_SEC 1
J 2
(3325 3225);
DISPLAY 0.680851 (3325 3225);
DISPLAY INVISIBLE (3325 3225);
FORCEADD Q_CAP_DIFFBUS..2
R 2
(3150 3100);
FORCEPROP 1 LAST PART_NUMBER SP_CH4221MEE01
J 2
(3034 3188);
DISPLAY 0.574468 (3034 3188);
PAINT GREEN (3034 3188);
DISPLAY INVISIBLE (3034 3188);
FORCEPROP 2 LAST VALUE DIFF BUS_0.22UF
J 2
(3000 3100);
DISPLAY 0.553191 (3000 3100);
FORCEPROP 1 LAST $LOCATION C683
J 2
(3384 3117);
DISPLAY 0.723404 (3384 3117);
PAINT GREEN (3384 3117);
FORCEPROP 2 LASTPIN (3225 3100) $PN 1
J 0
(3235 3110);
DISPLAY 0.808511 (3235 3110);
FORCEPROP 2 LASTPIN (3075 3100) $PN 2
J 2
(3065 3110);
DISPLAY 0.808511 (3065 3110);
FORCEPROP 2 LAST TOLERANCE 20%
J 2
(3075 3150);
DISPLAY 0.553191 (3075 3150);
DISPLAY INVISIBLE (3075 3150);
FORCEPROP 2 LAST PACK_TYPE C0201
J 2
(2975 3150);
DISPLAY 0.553191 (2975 3150);
DISPLAY INVISIBLE (2975 3150);
FORCEPROP 1 LAST MATERIAL X6S
J 2
(3159 3179);
DISPLAY 0.574468 (3159 3179);
PAINT GREEN (3159 3179);
DISPLAY INVISIBLE (3159 3179);
FORCEPROP 2 LAST VOLTAGE 6.3V
J 2
(2800 3150);
DISPLAY 0.553191 (2800 3150);
DISPLAY INVISIBLE (2800 3150);
FORCEPROP 1 LAST PIN_NAMES_ROTATE TRUE
J 2
(3150 3100);
DISPLAY 0.489362 (3150 3100);
PAINT GREEN (3150 3100);
DISPLAY INVISIBLE (3150 3100);
FORCEPROP 2 LAST CDS_LIB pure_quanta
J 2
(3150 3100);
DISPLAY INVISIBLE (3150 3100);
FORCEPROP 1 LAST CDS_LMAN_SYM_OUTLINE -25,50,25,-50
J 2
(3150 3100);
DISPLAY 0.468085 (3150 3100);
PAINT GREEN (3150 3100);
DISPLAY INVISIBLE (3150 3100);
FORCEPROP 1 LAST PATH I168
J 2
(3150 3100);
DISPLAY 0.723404 (3150 3100);
DISPLAY INVISIBLE (3150 3100);
FORCEPROP 1 LAST $LOCATION C683
J 0
(3400 3175);
DISPLAY 1.021277 (3400 3175);
DISPLAY INVISIBLE (3400 3175);
FORCEPROP 2 LAST CDS_LOCATION C683
J 0
(3400 3175);
DISPLAY 1.021277 (3400 3175);
DISPLAY INVISIBLE (3400 3175);
FORCEPROP 2 LAST $SEC 1
J 2
(3325 3175);
DISPLAY 0.680851 (3325 3175);
PAINT MONO (3325 3175);
DISPLAY INVISIBLE (3325 3175);
FORCEPROP 2 LAST CDS_SEC 1
J 2
(3325 3175);
DISPLAY 0.680851 (3325 3175);
DISPLAY INVISIBLE (3325 3175);
FORCEADD Q_CAP_DIFFBUS..2
R 2
(3150 3500);
FORCEPROP 1 LAST PART_NUMBER SP_CH4221MEE01
J 2
(3034 3588);
DISPLAY 0.574468 (3034 3588);
PAINT GREEN (3034 3588);
DISPLAY INVISIBLE (3034 3588);
FORCEPROP 2 LAST VALUE DIFF BUS_0.22UF
J 2
(3000 3500);
DISPLAY 0.553191 (3000 3500);
FORCEPROP 1 LAST $LOCATION C679
J 2
(3384 3517);
DISPLAY 0.723404 (3384 3517);
PAINT GREEN (3384 3517);
FORCEPROP 2 LASTPIN (3225 3500) $PN 1
J 0
(3235 3510);
DISPLAY 0.808511 (3235 3510);
FORCEPROP 2 LASTPIN (3075 3500) $PN 2
J 2
(3065 3510);
DISPLAY 0.808511 (3065 3510);
FORCEPROP 2 LAST TOLERANCE 20%
J 2
(3075 3550);
DISPLAY 0.553191 (3075 3550);
DISPLAY INVISIBLE (3075 3550);
FORCEPROP 2 LAST PACK_TYPE C0201
J 2
(2975 3550);
DISPLAY 0.553191 (2975 3550);
DISPLAY INVISIBLE (2975 3550);
FORCEPROP 1 LAST MATERIAL X6S
J 2
(3159 3579);
DISPLAY 0.574468 (3159 3579);
PAINT GREEN (3159 3579);
DISPLAY INVISIBLE (3159 3579);
FORCEPROP 2 LAST VOLTAGE 6.3V
J 2
(2800 3550);
DISPLAY 0.553191 (2800 3550);
DISPLAY INVISIBLE (2800 3550);
FORCEPROP 1 LAST PIN_NAMES_ROTATE TRUE
J 2
(3150 3500);
DISPLAY 0.489362 (3150 3500);
PAINT GREEN (3150 3500);
DISPLAY INVISIBLE (3150 3500);
FORCEPROP 2 LAST CDS_LIB pure_quanta
J 2
(3150 3500);
DISPLAY INVISIBLE (3150 3500);
FORCEPROP 1 LAST CDS_LMAN_SYM_OUTLINE -25,50,25,-50
J 2
(3150 3500);
DISPLAY 0.468085 (3150 3500);
PAINT GREEN (3150 3500);
DISPLAY INVISIBLE (3150 3500);
FORCEPROP 1 LAST PATH I169
J 2
(3150 3500);
DISPLAY 0.723404 (3150 3500);
DISPLAY INVISIBLE (3150 3500);
FORCEPROP 1 LAST $LOCATION C679
J 0
(3400 3575);
DISPLAY 1.021277 (3400 3575);
DISPLAY INVISIBLE (3400 3575);
FORCEPROP 2 LAST CDS_LOCATION C679
J 0
(3400 3575);
DISPLAY 1.021277 (3400 3575);
DISPLAY INVISIBLE (3400 3575);
FORCEPROP 2 LAST $SEC 1
J 2
(3325 3575);
DISPLAY 0.680851 (3325 3575);
PAINT MONO (3325 3575);
DISPLAY INVISIBLE (3325 3575);
FORCEPROP 2 LAST CDS_SEC 1
J 2
(3325 3575);
DISPLAY 0.680851 (3325 3575);
DISPLAY INVISIBLE (3325 3575);
FORCEADD Q_CAP_DIFFBUS..2
R 2
(3150 3350);
FORCEPROP 1 LAST PART_NUMBER SP_CH4221MEE01
J 2
(3034 3438);
DISPLAY 0.574468 (3034 3438);
PAINT GREEN (3034 3438);
DISPLAY INVISIBLE (3034 3438);
FORCEPROP 2 LAST VALUE DIFF BUS_0.22UF
J 2
(3000 3350);
DISPLAY 0.553191 (3000 3350);
FORCEPROP 1 LAST $LOCATION C680
J 2
(3384 3367);
DISPLAY 0.723404 (3384 3367);
PAINT GREEN (3384 3367);
FORCEPROP 2 LASTPIN (3225 3350) $PN 1
J 0
(3235 3360);
DISPLAY 0.808511 (3235 3360);
FORCEPROP 2 LASTPIN (3075 3350) $PN 2
J 2
(3065 3360);
DISPLAY 0.808511 (3065 3360);
FORCEPROP 2 LAST TOLERANCE 20%
J 2
(3075 3400);
DISPLAY 0.553191 (3075 3400);
DISPLAY INVISIBLE (3075 3400);
FORCEPROP 2 LAST PACK_TYPE C0201
J 2
(2975 3400);
DISPLAY 0.553191 (2975 3400);
DISPLAY INVISIBLE (2975 3400);
FORCEPROP 1 LAST MATERIAL X6S
J 2
(3159 3429);
DISPLAY 0.574468 (3159 3429);
PAINT GREEN (3159 3429);
DISPLAY INVISIBLE (3159 3429);
FORCEPROP 2 LAST VOLTAGE 6.3V
J 2
(2800 3400);
DISPLAY 0.553191 (2800 3400);
DISPLAY INVISIBLE (2800 3400);
FORCEPROP 1 LAST PIN_NAMES_ROTATE TRUE
J 2
(3150 3350);
DISPLAY 0.489362 (3150 3350);
PAINT GREEN (3150 3350);
DISPLAY INVISIBLE (3150 3350);
FORCEPROP 2 LAST CDS_LIB pure_quanta
J 2
(3150 3350);
DISPLAY INVISIBLE (3150 3350);
FORCEPROP 1 LAST CDS_LMAN_SYM_OUTLINE -25,50,25,-50
J 2
(3150 3350);
DISPLAY 0.468085 (3150 3350);
PAINT GREEN (3150 3350);
DISPLAY INVISIBLE (3150 3350);
FORCEPROP 1 LAST PATH I170
J 2
(3150 3350);
DISPLAY 0.723404 (3150 3350);
DISPLAY INVISIBLE (3150 3350);
FORCEPROP 1 LAST $LOCATION C680
J 0
(3400 3425);
DISPLAY 1.021277 (3400 3425);
DISPLAY INVISIBLE (3400 3425);
FORCEPROP 2 LAST CDS_LOCATION C680
J 0
(3400 3425);
DISPLAY 1.021277 (3400 3425);
DISPLAY INVISIBLE (3400 3425);
FORCEPROP 2 LAST $SEC 1
J 2
(3325 3425);
DISPLAY 0.680851 (3325 3425);
PAINT MONO (3325 3425);
DISPLAY INVISIBLE (3325 3425);
FORCEPROP 2 LAST CDS_SEC 1
J 2
(3325 3425);
DISPLAY 0.680851 (3325 3425);
DISPLAY INVISIBLE (3325 3425);
FORCEADD Q_CAP_DIFFBUS..2
R 2
(3150 3300);
FORCEPROP 1 LAST PART_NUMBER SP_CH4221MEE01
J 2
(3034 3388);
DISPLAY 0.574468 (3034 3388);
PAINT GREEN (3034 3388);
DISPLAY INVISIBLE (3034 3388);
FORCEPROP 2 LAST VALUE DIFF BUS_0.22UF
J 2
(3000 3300);
DISPLAY 0.553191 (3000 3300);
FORCEPROP 1 LAST $LOCATION C681
J 2
(3384 3317);
DISPLAY 0.723404 (3384 3317);
PAINT GREEN (3384 3317);
FORCEPROP 2 LASTPIN (3225 3300) $PN 1
J 0
(3235 3310);
DISPLAY 0.808511 (3235 3310);
FORCEPROP 2 LASTPIN (3075 3300) $PN 2
J 2
(3065 3310);
DISPLAY 0.808511 (3065 3310);
FORCEPROP 2 LAST TOLERANCE 20%
J 2
(3075 3350);
DISPLAY 0.553191 (3075 3350);
DISPLAY INVISIBLE (3075 3350);
FORCEPROP 2 LAST PACK_TYPE C0201
J 2
(2975 3350);
DISPLAY 0.553191 (2975 3350);
DISPLAY INVISIBLE (2975 3350);
FORCEPROP 1 LAST MATERIAL X6S
J 2
(3159 3379);
DISPLAY 0.574468 (3159 3379);
PAINT GREEN (3159 3379);
DISPLAY INVISIBLE (3159 3379);
FORCEPROP 2 LAST VOLTAGE 6.3V
J 2
(2800 3350);
DISPLAY 0.553191 (2800 3350);
DISPLAY INVISIBLE (2800 3350);
FORCEPROP 1 LAST PIN_NAMES_ROTATE TRUE
J 2
(3150 3300);
DISPLAY 0.489362 (3150 3300);
PAINT GREEN (3150 3300);
DISPLAY INVISIBLE (3150 3300);
FORCEPROP 2 LAST CDS_LIB pure_quanta
J 2
(3150 3300);
DISPLAY INVISIBLE (3150 3300);
FORCEPROP 1 LAST CDS_LMAN_SYM_OUTLINE -25,50,25,-50
J 2
(3150 3300);
DISPLAY 0.468085 (3150 3300);
PAINT GREEN (3150 3300);
DISPLAY INVISIBLE (3150 3300);
FORCEPROP 1 LAST PATH I171
J 2
(3150 3300);
DISPLAY 0.723404 (3150 3300);
DISPLAY INVISIBLE (3150 3300);
FORCEPROP 1 LAST $LOCATION C681
J 0
(3400 3375);
DISPLAY 1.021277 (3400 3375);
DISPLAY INVISIBLE (3400 3375);
FORCEPROP 2 LAST CDS_LOCATION C681
J 0
(3400 3375);
DISPLAY 1.021277 (3400 3375);
DISPLAY INVISIBLE (3400 3375);
FORCEPROP 2 LAST $SEC 1
J 2
(3325 3375);
DISPLAY 0.680851 (3325 3375);
PAINT MONO (3325 3375);
DISPLAY INVISIBLE (3325 3375);
FORCEPROP 2 LAST CDS_SEC 1
J 2
(3325 3375);
DISPLAY 0.680851 (3325 3375);
DISPLAY INVISIBLE (3325 3375);
FORCEADD Q_CAP_DIFFBUS..2
R 2
(3150 3550);
FORCEPROP 1 LAST PART_NUMBER SP_CH4221MEE01
J 2
(3409 3638);
DISPLAY 0.574468 (3409 3638);
PAINT GREEN (3409 3638);
DISPLAY INVISIBLE (3409 3638);
FORCEPROP 2 LAST TOLERANCE 20%
J 2
(3250 3700);
DISPLAY 0.553191 (3250 3700);
PAINT GREEN (3250 3700);
FORCEPROP 2 LAST VOLTAGE 6.3V
J 2
(3400 3700);
DISPLAY 0.553191 (3400 3700);
PAINT GREEN (3400 3700);
FORCEPROP 2 LAST PACK_TYPE C0201
J 2
(3150 3700);
DISPLAY 0.553191 (3150 3700);
PAINT GREEN (3150 3700);
FORCEPROP 1 LAST MATERIAL X6S
J 2
(3109 3754);
DISPLAY 0.574468 (3109 3754);
PAINT GREEN (3109 3754);
FORCEPROP 2 LAST VALUE DIFF BUS_0.22UF
J 2
(3000 3550);
DISPLAY 0.553191 (3000 3550);
FORCEPROP 1 LAST $LOCATION C678
J 2
(3384 3567);
DISPLAY 0.723404 (3384 3567);
PAINT GREEN (3384 3567);
FORCEPROP 2 LASTPIN (3225 3550) $PN 1
J 0
(3235 3560);
DISPLAY 0.808511 (3235 3560);
FORCEPROP 2 LASTPIN (3075 3550) $PN 2
J 2
(3065 3560);
DISPLAY 0.808511 (3065 3560);
FORCEPROP 1 LAST PIN_NAMES_ROTATE TRUE
J 2
(3150 3550);
DISPLAY 0.489362 (3150 3550);
PAINT GREEN (3150 3550);
DISPLAY INVISIBLE (3150 3550);
FORCEPROP 1 LAST CDS_LMAN_SYM_OUTLINE -25,50,25,-50
J 2
(3150 3550);
DISPLAY 0.468085 (3150 3550);
PAINT GREEN (3150 3550);
DISPLAY INVISIBLE (3150 3550);
FORCEPROP 2 LAST CDS_LIB pure_quanta
J 2
(3150 3550);
DISPLAY INVISIBLE (3150 3550);
FORCEPROP 1 LAST PATH I172
J 2
(3150 3550);
DISPLAY 0.723404 (3150 3550);
DISPLAY INVISIBLE (3150 3550);
FORCEPROP 1 LAST $LOCATION C678
J 0
(3400 3625);
DISPLAY 1.021277 (3400 3625);
DISPLAY INVISIBLE (3400 3625);
FORCEPROP 2 LAST CDS_LOCATION C678
J 0
(3125 3800);
DISPLAY 1.021277 (3125 3800);
DISPLAY INVISIBLE (3125 3800);
FORCEPROP 2 LAST $SEC 1
J 2
(3325 3625);
DISPLAY 0.680851 (3325 3625);
PAINT MONO (3325 3625);
DISPLAY INVISIBLE (3325 3625);
FORCEPROP 2 LAST CDS_SEC 1
J 2
(3325 3625);
DISPLAY 0.680851 (3325 3625);
DISPLAY INVISIBLE (3325 3625);
FORCEADD TAP..1
(3700 175);
FORCEPROP 3 LASTPIN (3650 175) SIG_NAME P5E_CPU1_PE4_TX_C_DN<0>
J 0
(3660 185);
DISPLAY 0.659574 (3660 185);
PAINT MONO (3660 185);
DISPLAY INVISIBLE (3660 185);
FORCEPROP 1 LASTPIN (3650 175) BN 0
J 0
(3638 183);
DISPLAY 0.680851 (3638 183);
PAINT GREEN (3638 183);
FORCEPROP 2 LAST CDS_LIB standard
J 0
(3700 175);
DISPLAY INVISIBLE (3700 175);
FORCEPROP 1 LAST BODY_TYPE PLUMBING
J 0
(3700 225);
DISPLAY 0.872340 (3700 225);
PAINT GREEN (3700 225);
DISPLAY INVISIBLE (3700 225);
FORCEPROP 1 LAST HDL_TAP TRUE
J 0
(4025 50);
DISPLAY 0.872340 (4025 50);
DISPLAY INVISIBLE (4025 50);
FORCEPROP 1 LAST PATH I173
J 0
(3698 175);
DISPLAY 0.872340 (3698 175);
PAINT GREEN (3698 175);
DISPLAY INVISIBLE (3698 175);
FORCEADD TAP..1
(3900 125);
FORCEPROP 3 LASTPIN (3850 125) SIG_NAME P5E_CPU1_PE4_TX_C_DP<0>
J 0
(3860 135);
DISPLAY 0.659574 (3860 135);
PAINT MONO (3860 135);
DISPLAY INVISIBLE (3860 135);
FORCEPROP 1 LASTPIN (3850 125) BN 0
J 0
(3838 133);
DISPLAY 0.680851 (3838 133);
PAINT GREEN (3838 133);
FORCEPROP 2 LAST CDS_LIB standard
J 0
(3900 125);
DISPLAY INVISIBLE (3900 125);
FORCEPROP 1 LAST BODY_TYPE PLUMBING
J 0
(3900 175);
DISPLAY 0.872340 (3900 175);
PAINT GREEN (3900 175);
DISPLAY INVISIBLE (3900 175);
FORCEPROP 1 LAST HDL_TAP TRUE
J 0
(4225 0);
DISPLAY 0.872340 (4225 0);
DISPLAY INVISIBLE (4225 0);
FORCEPROP 1 LAST PATH I174
J 0
(3898 125);
DISPLAY 0.872340 (3898 125);
PAINT GREEN (3898 125);
DISPLAY INVISIBLE (3898 125);
FORCEADD TAP..1
(3700 375);
FORCEPROP 3 LASTPIN (3650 375) SIG_NAME P5E_CPU1_PE4_TX_C_DN<1>
J 0
(3660 385);
DISPLAY 0.659574 (3660 385);
PAINT MONO (3660 385);
DISPLAY INVISIBLE (3660 385);
FORCEPROP 1 LASTPIN (3650 375) BN 1
J 0
(3638 383);
DISPLAY 0.680851 (3638 383);
PAINT GREEN (3638 383);
FORCEPROP 2 LAST CDS_LIB standard
J 0
(3700 375);
DISPLAY INVISIBLE (3700 375);
FORCEPROP 1 LAST BODY_TYPE PLUMBING
J 0
(3700 425);
DISPLAY 0.872340 (3700 425);
PAINT GREEN (3700 425);
DISPLAY INVISIBLE (3700 425);
FORCEPROP 1 LAST HDL_TAP TRUE
J 0
(4025 250);
DISPLAY 0.872340 (4025 250);
DISPLAY INVISIBLE (4025 250);
FORCEPROP 1 LAST PATH I175
J 0
(3698 375);
DISPLAY 0.872340 (3698 375);
PAINT GREEN (3698 375);
DISPLAY INVISIBLE (3698 375);
FORCEADD TAP..1
(3900 325);
FORCEPROP 3 LASTPIN (3850 325) SIG_NAME P5E_CPU1_PE4_TX_C_DP<1>
J 0
(3860 335);
DISPLAY 0.659574 (3860 335);
PAINT MONO (3860 335);
DISPLAY INVISIBLE (3860 335);
FORCEPROP 1 LASTPIN (3850 325) BN 1
J 0
(3838 333);
DISPLAY 0.680851 (3838 333);
PAINT GREEN (3838 333);
FORCEPROP 2 LAST CDS_LIB standard
J 0
(3900 325);
DISPLAY INVISIBLE (3900 325);
FORCEPROP 1 LAST BODY_TYPE PLUMBING
J 0
(3900 375);
DISPLAY 0.872340 (3900 375);
PAINT GREEN (3900 375);
DISPLAY INVISIBLE (3900 375);
FORCEPROP 1 LAST HDL_TAP TRUE
J 0
(4225 200);
DISPLAY 0.872340 (4225 200);
DISPLAY INVISIBLE (4225 200);
FORCEPROP 1 LAST PATH I176
J 0
(3898 325);
DISPLAY 0.872340 (3898 325);
PAINT GREEN (3898 325);
DISPLAY INVISIBLE (3898 325);
FORCEADD TAP..1
(3700 575);
FORCEPROP 3 LASTPIN (3650 575) SIG_NAME P5E_CPU1_PE4_TX_C_DN<2>
J 0
(3660 585);
DISPLAY 0.659574 (3660 585);
PAINT MONO (3660 585);
DISPLAY INVISIBLE (3660 585);
FORCEPROP 1 LASTPIN (3650 575) BN 2
J 0
(3638 583);
DISPLAY 0.680851 (3638 583);
PAINT GREEN (3638 583);
FORCEPROP 2 LAST CDS_LIB standard
J 0
(3700 575);
DISPLAY INVISIBLE (3700 575);
FORCEPROP 1 LAST BODY_TYPE PLUMBING
J 0
(3700 625);
DISPLAY 0.872340 (3700 625);
PAINT GREEN (3700 625);
DISPLAY INVISIBLE (3700 625);
FORCEPROP 1 LAST HDL_TAP TRUE
J 0
(4025 450);
DISPLAY 0.872340 (4025 450);
DISPLAY INVISIBLE (4025 450);
FORCEPROP 1 LAST PATH I177
J 0
(3698 575);
DISPLAY 0.872340 (3698 575);
PAINT GREEN (3698 575);
DISPLAY INVISIBLE (3698 575);
FORCEADD TAP..1
(3900 525);
FORCEPROP 3 LASTPIN (3850 525) SIG_NAME P5E_CPU1_PE4_TX_C_DP<2>
J 0
(3860 535);
DISPLAY 0.659574 (3860 535);
PAINT MONO (3860 535);
DISPLAY INVISIBLE (3860 535);
FORCEPROP 1 LASTPIN (3850 525) BN 2
J 0
(3838 533);
DISPLAY 0.680851 (3838 533);
PAINT GREEN (3838 533);
FORCEPROP 2 LAST CDS_LIB standard
J 0
(3900 525);
DISPLAY INVISIBLE (3900 525);
FORCEPROP 1 LAST BODY_TYPE PLUMBING
J 0
(3900 575);
DISPLAY 0.872340 (3900 575);
PAINT GREEN (3900 575);
DISPLAY INVISIBLE (3900 575);
FORCEPROP 1 LAST HDL_TAP TRUE
J 0
(4225 400);
DISPLAY 0.872340 (4225 400);
DISPLAY INVISIBLE (4225 400);
FORCEPROP 1 LAST PATH I178
J 0
(3898 525);
DISPLAY 0.872340 (3898 525);
PAINT GREEN (3898 525);
DISPLAY INVISIBLE (3898 525);
FORCEADD TAP..1
(3700 775);
FORCEPROP 3 LASTPIN (3650 775) SIG_NAME P5E_CPU1_PE4_TX_C_DN<3>
J 0
(3660 785);
DISPLAY 0.659574 (3660 785);
PAINT MONO (3660 785);
DISPLAY INVISIBLE (3660 785);
FORCEPROP 1 LASTPIN (3650 775) BN 3
J 0
(3638 783);
DISPLAY 0.680851 (3638 783);
PAINT GREEN (3638 783);
FORCEPROP 2 LAST CDS_LIB standard
J 0
(3700 775);
DISPLAY INVISIBLE (3700 775);
FORCEPROP 1 LAST BODY_TYPE PLUMBING
J 0
(3700 825);
DISPLAY 0.872340 (3700 825);
PAINT GREEN (3700 825);
DISPLAY INVISIBLE (3700 825);
FORCEPROP 1 LAST HDL_TAP TRUE
J 0
(4025 650);
DISPLAY 0.872340 (4025 650);
DISPLAY INVISIBLE (4025 650);
FORCEPROP 1 LAST PATH I179
J 0
(3698 775);
DISPLAY 0.872340 (3698 775);
PAINT GREEN (3698 775);
DISPLAY INVISIBLE (3698 775);
FORCEADD TAP..1
(3900 725);
FORCEPROP 3 LASTPIN (3850 725) SIG_NAME P5E_CPU1_PE4_TX_C_DP<3>
J 0
(3860 735);
DISPLAY 0.659574 (3860 735);
PAINT MONO (3860 735);
DISPLAY INVISIBLE (3860 735);
FORCEPROP 1 LASTPIN (3850 725) BN 3
J 0
(3838 733);
DISPLAY 0.680851 (3838 733);
PAINT GREEN (3838 733);
FORCEPROP 2 LAST CDS_LIB standard
J 0
(3900 725);
DISPLAY INVISIBLE (3900 725);
FORCEPROP 1 LAST BODY_TYPE PLUMBING
J 0
(3900 775);
DISPLAY 0.872340 (3900 775);
PAINT GREEN (3900 775);
DISPLAY INVISIBLE (3900 775);
FORCEPROP 1 LAST HDL_TAP TRUE
J 0
(4225 600);
DISPLAY 0.872340 (4225 600);
DISPLAY INVISIBLE (4225 600);
FORCEPROP 1 LAST PATH I180
J 0
(3898 725);
DISPLAY 0.872340 (3898 725);
PAINT GREEN (3898 725);
DISPLAY INVISIBLE (3898 725);
FORCEADD TAP..1
(3900 925);
FORCEPROP 3 LASTPIN (3850 925) SIG_NAME P5E_CPU1_PE4_TX_C_DP<4>
J 0
(3860 935);
DISPLAY 0.659574 (3860 935);
PAINT MONO (3860 935);
DISPLAY INVISIBLE (3860 935);
FORCEPROP 1 LASTPIN (3850 925) BN 4
J 0
(3838 933);
DISPLAY 0.680851 (3838 933);
PAINT GREEN (3838 933);
FORCEPROP 2 LAST CDS_LIB standard
J 0
(3900 925);
DISPLAY INVISIBLE (3900 925);
FORCEPROP 1 LAST BODY_TYPE PLUMBING
J 0
(3900 975);
DISPLAY 0.872340 (3900 975);
PAINT GREEN (3900 975);
DISPLAY INVISIBLE (3900 975);
FORCEPROP 1 LAST HDL_TAP TRUE
J 0
(4225 800);
DISPLAY 0.872340 (4225 800);
DISPLAY INVISIBLE (4225 800);
FORCEPROP 1 LAST PATH I181
J 0
(3898 925);
DISPLAY 0.872340 (3898 925);
PAINT GREEN (3898 925);
DISPLAY INVISIBLE (3898 925);
FORCEADD TAP..1
(3700 1175);
FORCEPROP 3 LASTPIN (3650 1175) SIG_NAME P5E_CPU1_PE4_TX_C_DN<5>
J 0
(3660 1185);
DISPLAY 0.659574 (3660 1185);
PAINT MONO (3660 1185);
DISPLAY INVISIBLE (3660 1185);
FORCEPROP 1 LASTPIN (3650 1175) BN 5
J 0
(3638 1183);
DISPLAY 0.680851 (3638 1183);
PAINT GREEN (3638 1183);
FORCEPROP 2 LAST CDS_LIB standard
J 0
(3700 1175);
DISPLAY INVISIBLE (3700 1175);
FORCEPROP 1 LAST BODY_TYPE PLUMBING
J 0
(3700 1225);
DISPLAY 0.872340 (3700 1225);
PAINT GREEN (3700 1225);
DISPLAY INVISIBLE (3700 1225);
FORCEPROP 1 LAST HDL_TAP TRUE
J 0
(4025 1050);
DISPLAY 0.872340 (4025 1050);
DISPLAY INVISIBLE (4025 1050);
FORCEPROP 1 LAST PATH I182
J 0
(3698 1175);
DISPLAY 0.872340 (3698 1175);
PAINT GREEN (3698 1175);
DISPLAY INVISIBLE (3698 1175);
FORCEADD TAP..1
(3700 975);
FORCEPROP 3 LASTPIN (3650 975) SIG_NAME P5E_CPU1_PE4_TX_C_DN<4>
J 0
(3660 985);
DISPLAY 0.659574 (3660 985);
PAINT MONO (3660 985);
DISPLAY INVISIBLE (3660 985);
FORCEPROP 1 LASTPIN (3650 975) BN 4
J 0
(3638 983);
DISPLAY 0.680851 (3638 983);
PAINT GREEN (3638 983);
FORCEPROP 2 LAST CDS_LIB standard
J 0
(3700 975);
DISPLAY INVISIBLE (3700 975);
FORCEPROP 1 LAST BODY_TYPE PLUMBING
J 0
(3700 1025);
DISPLAY 0.872340 (3700 1025);
PAINT GREEN (3700 1025);
DISPLAY INVISIBLE (3700 1025);
FORCEPROP 1 LAST HDL_TAP TRUE
J 0
(4025 850);
DISPLAY 0.872340 (4025 850);
DISPLAY INVISIBLE (4025 850);
FORCEPROP 1 LAST PATH I183
J 0
(3698 975);
DISPLAY 0.872340 (3698 975);
PAINT GREEN (3698 975);
DISPLAY INVISIBLE (3698 975);
FORCEADD TAP..1
(3900 1125);
FORCEPROP 3 LASTPIN (3850 1125) SIG_NAME P5E_CPU1_PE4_TX_C_DP<5>
J 0
(3860 1135);
DISPLAY 0.659574 (3860 1135);
PAINT MONO (3860 1135);
DISPLAY INVISIBLE (3860 1135);
FORCEPROP 1 LASTPIN (3850 1125) BN 5
J 0
(3838 1133);
DISPLAY 0.680851 (3838 1133);
PAINT GREEN (3838 1133);
FORCEPROP 2 LAST CDS_LIB standard
J 0
(3900 1125);
DISPLAY INVISIBLE (3900 1125);
FORCEPROP 1 LAST BODY_TYPE PLUMBING
J 0
(3900 1175);
DISPLAY 0.872340 (3900 1175);
PAINT GREEN (3900 1175);
DISPLAY INVISIBLE (3900 1175);
FORCEPROP 1 LAST HDL_TAP TRUE
J 0
(4225 1000);
DISPLAY 0.872340 (4225 1000);
DISPLAY INVISIBLE (4225 1000);
FORCEPROP 1 LAST PATH I184
J 0
(3898 1125);
DISPLAY 0.872340 (3898 1125);
PAINT GREEN (3898 1125);
DISPLAY INVISIBLE (3898 1125);
FORCEADD TAP..1
(3700 1375);
FORCEPROP 3 LASTPIN (3650 1375) SIG_NAME P5E_CPU1_PE4_TX_C_DN<6>
J 0
(3660 1385);
DISPLAY 0.659574 (3660 1385);
PAINT MONO (3660 1385);
DISPLAY INVISIBLE (3660 1385);
FORCEPROP 1 LASTPIN (3650 1375) BN 6
J 0
(3638 1383);
DISPLAY 0.680851 (3638 1383);
PAINT GREEN (3638 1383);
FORCEPROP 2 LAST CDS_LIB standard
J 0
(3700 1375);
DISPLAY INVISIBLE (3700 1375);
FORCEPROP 1 LAST BODY_TYPE PLUMBING
J 0
(3700 1425);
DISPLAY 0.872340 (3700 1425);
PAINT GREEN (3700 1425);
DISPLAY INVISIBLE (3700 1425);
FORCEPROP 1 LAST HDL_TAP TRUE
J 0
(4025 1250);
DISPLAY 0.872340 (4025 1250);
DISPLAY INVISIBLE (4025 1250);
FORCEPROP 1 LAST PATH I185
J 0
(3698 1375);
DISPLAY 0.872340 (3698 1375);
PAINT GREEN (3698 1375);
DISPLAY INVISIBLE (3698 1375);
FORCEADD TAP..1
(3900 1325);
FORCEPROP 3 LASTPIN (3850 1325) SIG_NAME P5E_CPU1_PE4_TX_C_DP<6>
J 0
(3860 1335);
DISPLAY 0.659574 (3860 1335);
PAINT MONO (3860 1335);
DISPLAY INVISIBLE (3860 1335);
FORCEPROP 1 LASTPIN (3850 1325) BN 6
J 0
(3838 1333);
DISPLAY 0.680851 (3838 1333);
PAINT GREEN (3838 1333);
FORCEPROP 2 LAST CDS_LIB standard
J 0
(3900 1325);
DISPLAY INVISIBLE (3900 1325);
FORCEPROP 1 LAST BODY_TYPE PLUMBING
J 0
(3900 1375);
DISPLAY 0.872340 (3900 1375);
PAINT GREEN (3900 1375);
DISPLAY INVISIBLE (3900 1375);
FORCEPROP 1 LAST HDL_TAP TRUE
J 0
(4225 1200);
DISPLAY 0.872340 (4225 1200);
DISPLAY INVISIBLE (4225 1200);
FORCEPROP 1 LAST PATH I186
J 0
(3898 1325);
DISPLAY 0.872340 (3898 1325);
PAINT GREEN (3898 1325);
DISPLAY INVISIBLE (3898 1325);
FORCEADD TAP..1
(3900 1525);
FORCEPROP 3 LASTPIN (3850 1525) SIG_NAME P5E_CPU1_PE4_TX_C_DP<7>
J 0
(3860 1535);
DISPLAY 0.659574 (3860 1535);
PAINT MONO (3860 1535);
DISPLAY INVISIBLE (3860 1535);
FORCEPROP 1 LASTPIN (3850 1525) BN 7
J 0
(3838 1533);
DISPLAY 0.680851 (3838 1533);
PAINT GREEN (3838 1533);
FORCEPROP 2 LAST CDS_LIB standard
J 0
(3900 1525);
DISPLAY INVISIBLE (3900 1525);
FORCEPROP 1 LAST BODY_TYPE PLUMBING
J 0
(3900 1575);
DISPLAY 0.872340 (3900 1575);
PAINT GREEN (3900 1575);
DISPLAY INVISIBLE (3900 1575);
FORCEPROP 1 LAST HDL_TAP TRUE
J 0
(4225 1400);
DISPLAY 0.872340 (4225 1400);
DISPLAY INVISIBLE (4225 1400);
FORCEPROP 1 LAST PATH I187
J 0
(3898 1525);
DISPLAY 0.872340 (3898 1525);
PAINT GREEN (3898 1525);
DISPLAY INVISIBLE (3898 1525);
FORCEADD TAP..1
(3700 1575);
FORCEPROP 3 LASTPIN (3650 1575) SIG_NAME P5E_CPU1_PE4_TX_C_DN<7>
J 0
(3660 1585);
DISPLAY 0.659574 (3660 1585);
PAINT MONO (3660 1585);
DISPLAY INVISIBLE (3660 1585);
FORCEPROP 1 LASTPIN (3650 1575) BN 7
J 0
(3638 1583);
DISPLAY 0.680851 (3638 1583);
PAINT GREEN (3638 1583);
FORCEPROP 2 LAST CDS_LIB standard
J 0
(3700 1575);
DISPLAY INVISIBLE (3700 1575);
FORCEPROP 1 LAST BODY_TYPE PLUMBING
J 0
(3700 1625);
DISPLAY 0.872340 (3700 1625);
PAINT GREEN (3700 1625);
DISPLAY INVISIBLE (3700 1625);
FORCEPROP 1 LAST HDL_TAP TRUE
J 0
(4025 1450);
DISPLAY 0.872340 (4025 1450);
DISPLAY INVISIBLE (4025 1450);
FORCEPROP 1 LAST PATH I188
J 0
(3698 1575);
DISPLAY 0.872340 (3698 1575);
PAINT GREEN (3698 1575);
DISPLAY INVISIBLE (3698 1575);
FORCEADD OFFPAGE..2
(4900 1550);
FORCEPROP 2 LAST $XR0 143 
J 0
(5089 1550);
DISPLAY 0.638298 (5089 1550);
PAINT MONO (5089 1550);
FORCEPROP 2 LAST CDS_LIB standard
J 0
(4900 1550);
DISPLAY INVISIBLE (4900 1550);
FORCEPROP 1 LAST OFFPAGE TRUE
J 0
(5225 1425);
DISPLAY 0.872340 (5225 1425);
DISPLAY INVISIBLE (5225 1425);
FORCEPROP 1 LAST COMMENT_BODY TRUE
J 0
(4855 1455);
DISPLAY 0.872340 (4855 1455);
PAINT GREEN (4855 1455);
DISPLAY INVISIBLE (4855 1455);
FORCEPROP 2 LAST PATH I189
J 0
(5075 1625);
DISPLAY 1.021277 (5075 1625);
DISPLAY INVISIBLE (5075 1625);
FORCEADD OFFPAGE..2
(4900 1600);
FORCEPROP 2 LAST $XR0 143 
J 0
(5089 1600);
DISPLAY 0.638298 (5089 1600);
PAINT MONO (5089 1600);
FORCEPROP 2 LAST CDS_LIB standard
J 0
(4900 1600);
DISPLAY INVISIBLE (4900 1600);
FORCEPROP 1 LAST OFFPAGE TRUE
J 0
(5225 1475);
DISPLAY 0.872340 (5225 1475);
DISPLAY INVISIBLE (5225 1475);
FORCEPROP 1 LAST COMMENT_BODY TRUE
J 0
(4855 1505);
DISPLAY 0.872340 (4855 1505);
PAINT GREEN (4855 1505);
DISPLAY INVISIBLE (4855 1505);
FORCEPROP 2 LAST PATH I190
J 0
(5075 1675);
DISPLAY 1.021277 (5075 1675);
DISPLAY INVISIBLE (5075 1675);
FORCEADD TAP..1
(3700 2150);
FORCEPROP 3 LASTPIN (3650 2150) SIG_NAME P5E_CPU1_PE4_TX_C_DN<8>
J 0
(3660 2160);
DISPLAY 0.659574 (3660 2160);
PAINT MONO (3660 2160);
DISPLAY INVISIBLE (3660 2160);
FORCEPROP 1 LASTPIN (3650 2150) BN 8
J 0
(3638 2158);
DISPLAY 0.680851 (3638 2158);
PAINT GREEN (3638 2158);
FORCEPROP 2 LAST CDS_LIB standard
J 0
(3700 2150);
DISPLAY INVISIBLE (3700 2150);
FORCEPROP 1 LAST BODY_TYPE PLUMBING
J 0
(3700 2200);
DISPLAY 0.872340 (3700 2200);
PAINT GREEN (3700 2200);
DISPLAY INVISIBLE (3700 2200);
FORCEPROP 1 LAST HDL_TAP TRUE
J 0
(4025 2025);
DISPLAY 0.872340 (4025 2025);
DISPLAY INVISIBLE (4025 2025);
FORCEPROP 1 LAST PATH I191
J 0
(3698 2150);
DISPLAY 0.872340 (3698 2150);
PAINT GREEN (3698 2150);
DISPLAY INVISIBLE (3698 2150);
FORCEADD TAP..1
(3900 2100);
FORCEPROP 3 LASTPIN (3850 2100) SIG_NAME P5E_CPU1_PE4_TX_C_DP<8>
J 0
(3860 2110);
DISPLAY 0.659574 (3860 2110);
PAINT MONO (3860 2110);
DISPLAY INVISIBLE (3860 2110);
FORCEPROP 1 LASTPIN (3850 2100) BN 8
J 0
(3838 2108);
DISPLAY 0.680851 (3838 2108);
PAINT GREEN (3838 2108);
FORCEPROP 2 LAST CDS_LIB standard
J 0
(3900 2100);
DISPLAY INVISIBLE (3900 2100);
FORCEPROP 1 LAST BODY_TYPE PLUMBING
J 0
(3900 2150);
DISPLAY 0.872340 (3900 2150);
PAINT GREEN (3900 2150);
DISPLAY INVISIBLE (3900 2150);
FORCEPROP 1 LAST HDL_TAP TRUE
J 0
(4225 1975);
DISPLAY 0.872340 (4225 1975);
DISPLAY INVISIBLE (4225 1975);
FORCEPROP 1 LAST PATH I192
J 0
(3898 2100);
DISPLAY 0.872340 (3898 2100);
PAINT GREEN (3898 2100);
DISPLAY INVISIBLE (3898 2100);
FORCEADD TAP..1
(3900 2300);
FORCEPROP 3 LASTPIN (3850 2300) SIG_NAME P5E_CPU1_PE4_TX_C_DP<9>
J 0
(3860 2310);
DISPLAY 0.659574 (3860 2310);
PAINT MONO (3860 2310);
DISPLAY INVISIBLE (3860 2310);
FORCEPROP 1 LASTPIN (3850 2300) BN 9
J 0
(3838 2308);
DISPLAY 0.680851 (3838 2308);
PAINT GREEN (3838 2308);
FORCEPROP 2 LAST CDS_LIB standard
J 0
(3900 2300);
DISPLAY INVISIBLE (3900 2300);
FORCEPROP 1 LAST BODY_TYPE PLUMBING
J 0
(3900 2350);
DISPLAY 0.872340 (3900 2350);
PAINT GREEN (3900 2350);
DISPLAY INVISIBLE (3900 2350);
FORCEPROP 1 LAST HDL_TAP TRUE
J 0
(4225 2175);
DISPLAY 0.872340 (4225 2175);
DISPLAY INVISIBLE (4225 2175);
FORCEPROP 1 LAST PATH I193
J 0
(3898 2300);
DISPLAY 0.872340 (3898 2300);
PAINT GREEN (3898 2300);
DISPLAY INVISIBLE (3898 2300);
FORCEADD TAP..1
(3700 2350);
FORCEPROP 3 LASTPIN (3650 2350) SIG_NAME P5E_CPU1_PE4_TX_C_DN<9>
J 0
(3660 2360);
DISPLAY 0.659574 (3660 2360);
PAINT MONO (3660 2360);
DISPLAY INVISIBLE (3660 2360);
FORCEPROP 1 LASTPIN (3650 2350) BN 9
J 0
(3638 2358);
DISPLAY 0.680851 (3638 2358);
PAINT GREEN (3638 2358);
FORCEPROP 2 LAST CDS_LIB standard
J 0
(3700 2350);
DISPLAY INVISIBLE (3700 2350);
FORCEPROP 1 LAST BODY_TYPE PLUMBING
J 0
(3700 2400);
DISPLAY 0.872340 (3700 2400);
PAINT GREEN (3700 2400);
DISPLAY INVISIBLE (3700 2400);
FORCEPROP 1 LAST HDL_TAP TRUE
J 0
(4025 2225);
DISPLAY 0.872340 (4025 2225);
DISPLAY INVISIBLE (4025 2225);
FORCEPROP 1 LAST PATH I194
J 0
(3698 2350);
DISPLAY 0.872340 (3698 2350);
PAINT GREEN (3698 2350);
DISPLAY INVISIBLE (3698 2350);
FORCEADD TAP..1
(3700 2550);
FORCEPROP 3 LASTPIN (3650 2550) SIG_NAME P5E_CPU1_PE4_TX_C_DN<10>
J 0
(3660 2560);
DISPLAY 0.659574 (3660 2560);
PAINT MONO (3660 2560);
DISPLAY INVISIBLE (3660 2560);
FORCEPROP 1 LASTPIN (3650 2550) BN 10
J 0
(3638 2558);
DISPLAY 0.680851 (3638 2558);
PAINT GREEN (3638 2558);
FORCEPROP 2 LAST CDS_LIB standard
J 0
(3700 2550);
DISPLAY INVISIBLE (3700 2550);
FORCEPROP 1 LAST BODY_TYPE PLUMBING
J 0
(3700 2600);
DISPLAY 0.872340 (3700 2600);
PAINT GREEN (3700 2600);
DISPLAY INVISIBLE (3700 2600);
FORCEPROP 1 LAST HDL_TAP TRUE
J 0
(4025 2425);
DISPLAY 0.872340 (4025 2425);
DISPLAY INVISIBLE (4025 2425);
FORCEPROP 1 LAST PATH I195
J 0
(3698 2550);
DISPLAY 0.872340 (3698 2550);
PAINT GREEN (3698 2550);
DISPLAY INVISIBLE (3698 2550);
FORCEADD TAP..1
(3900 2700);
FORCEPROP 3 LASTPIN (3850 2700) SIG_NAME P5E_CPU1_PE4_TX_C_DP<11>
J 0
(3860 2710);
DISPLAY 0.659574 (3860 2710);
PAINT MONO (3860 2710);
DISPLAY INVISIBLE (3860 2710);
FORCEPROP 1 LASTPIN (3850 2700) BN 11
J 0
(3838 2708);
DISPLAY 0.680851 (3838 2708);
PAINT GREEN (3838 2708);
FORCEPROP 2 LAST CDS_LIB standard
J 0
(3900 2700);
DISPLAY INVISIBLE (3900 2700);
FORCEPROP 1 LAST BODY_TYPE PLUMBING
J 0
(3900 2750);
DISPLAY 0.872340 (3900 2750);
PAINT GREEN (3900 2750);
DISPLAY INVISIBLE (3900 2750);
FORCEPROP 1 LAST HDL_TAP TRUE
J 0
(4225 2575);
DISPLAY 0.872340 (4225 2575);
DISPLAY INVISIBLE (4225 2575);
FORCEPROP 1 LAST PATH I196
J 0
(3898 2700);
DISPLAY 0.872340 (3898 2700);
PAINT GREEN (3898 2700);
DISPLAY INVISIBLE (3898 2700);
FORCEADD TAP..1
(3900 2500);
FORCEPROP 3 LASTPIN (3850 2500) SIG_NAME P5E_CPU1_PE4_TX_C_DP<10>
J 0
(3860 2510);
DISPLAY 0.659574 (3860 2510);
PAINT MONO (3860 2510);
DISPLAY INVISIBLE (3860 2510);
FORCEPROP 1 LASTPIN (3850 2500) BN 10
J 0
(3838 2508);
DISPLAY 0.680851 (3838 2508);
PAINT GREEN (3838 2508);
FORCEPROP 2 LAST CDS_LIB standard
J 0
(3900 2500);
DISPLAY INVISIBLE (3900 2500);
FORCEPROP 1 LAST BODY_TYPE PLUMBING
J 0
(3900 2550);
DISPLAY 0.872340 (3900 2550);
PAINT GREEN (3900 2550);
DISPLAY INVISIBLE (3900 2550);
FORCEPROP 1 LAST HDL_TAP TRUE
J 0
(4225 2375);
DISPLAY 0.872340 (4225 2375);
DISPLAY INVISIBLE (4225 2375);
FORCEPROP 1 LAST PATH I197
J 0
(3898 2500);
DISPLAY 0.872340 (3898 2500);
PAINT GREEN (3898 2500);
DISPLAY INVISIBLE (3898 2500);
FORCEADD TAP..1
(3700 2950);
FORCEPROP 3 LASTPIN (3650 2950) SIG_NAME P5E_CPU1_PE4_TX_C_DN<12>
J 0
(3660 2960);
DISPLAY 0.659574 (3660 2960);
PAINT MONO (3660 2960);
DISPLAY INVISIBLE (3660 2960);
FORCEPROP 1 LASTPIN (3650 2950) BN 12
J 0
(3638 2958);
DISPLAY 0.680851 (3638 2958);
PAINT GREEN (3638 2958);
FORCEPROP 2 LAST CDS_LIB standard
J 0
(3700 2950);
DISPLAY INVISIBLE (3700 2950);
FORCEPROP 1 LAST BODY_TYPE PLUMBING
J 0
(3700 3000);
DISPLAY 0.872340 (3700 3000);
PAINT GREEN (3700 3000);
DISPLAY INVISIBLE (3700 3000);
FORCEPROP 1 LAST HDL_TAP TRUE
J 0
(4025 2825);
DISPLAY 0.872340 (4025 2825);
DISPLAY INVISIBLE (4025 2825);
FORCEPROP 1 LAST PATH I198
J 0
(3698 2950);
DISPLAY 0.872340 (3698 2950);
PAINT GREEN (3698 2950);
DISPLAY INVISIBLE (3698 2950);
FORCEADD TAP..1
(3700 2750);
FORCEPROP 3 LASTPIN (3650 2750) SIG_NAME P5E_CPU1_PE4_TX_C_DN<11>
J 0
(3660 2760);
DISPLAY 0.659574 (3660 2760);
PAINT MONO (3660 2760);
DISPLAY INVISIBLE (3660 2760);
FORCEPROP 1 LASTPIN (3650 2750) BN 11
J 0
(3638 2758);
DISPLAY 0.680851 (3638 2758);
PAINT GREEN (3638 2758);
FORCEPROP 2 LAST CDS_LIB standard
J 0
(3700 2750);
DISPLAY INVISIBLE (3700 2750);
FORCEPROP 1 LAST BODY_TYPE PLUMBING
J 0
(3700 2800);
DISPLAY 0.872340 (3700 2800);
PAINT GREEN (3700 2800);
DISPLAY INVISIBLE (3700 2800);
FORCEPROP 1 LAST HDL_TAP TRUE
J 0
(4025 2625);
DISPLAY 0.872340 (4025 2625);
DISPLAY INVISIBLE (4025 2625);
FORCEPROP 1 LAST PATH I199
J 0
(3698 2750);
DISPLAY 0.872340 (3698 2750);
PAINT GREEN (3698 2750);
DISPLAY INVISIBLE (3698 2750);
FORCEADD TAP..1
(3900 2900);
FORCEPROP 3 LASTPIN (3850 2900) SIG_NAME P5E_CPU1_PE4_TX_C_DP<12>
J 0
(3860 2910);
DISPLAY 0.659574 (3860 2910);
PAINT MONO (3860 2910);
DISPLAY INVISIBLE (3860 2910);
FORCEPROP 1 LASTPIN (3850 2900) BN 12
J 0
(3838 2908);
DISPLAY 0.680851 (3838 2908);
PAINT GREEN (3838 2908);
FORCEPROP 2 LAST CDS_LIB standard
J 0
(3900 2900);
DISPLAY INVISIBLE (3900 2900);
FORCEPROP 1 LAST BODY_TYPE PLUMBING
J 0
(3900 2950);
DISPLAY 0.872340 (3900 2950);
PAINT GREEN (3900 2950);
DISPLAY INVISIBLE (3900 2950);
FORCEPROP 1 LAST HDL_TAP TRUE
J 0
(4225 2775);
DISPLAY 0.872340 (4225 2775);
DISPLAY INVISIBLE (4225 2775);
FORCEPROP 1 LAST PATH I200
J 0
(3898 2900);
DISPLAY 0.872340 (3898 2900);
PAINT GREEN (3898 2900);
DISPLAY INVISIBLE (3898 2900);
FORCEADD TAP..1
(3700 3150);
FORCEPROP 3 LASTPIN (3650 3150) SIG_NAME P5E_CPU1_PE4_TX_C_DN<13>
J 0
(3660 3160);
DISPLAY 0.659574 (3660 3160);
PAINT MONO (3660 3160);
DISPLAY INVISIBLE (3660 3160);
FORCEPROP 1 LASTPIN (3650 3150) BN 13
J 0
(3638 3158);
DISPLAY 0.680851 (3638 3158);
PAINT GREEN (3638 3158);
FORCEPROP 2 LAST CDS_LIB standard
J 0
(3700 3150);
DISPLAY INVISIBLE (3700 3150);
FORCEPROP 1 LAST BODY_TYPE PLUMBING
J 0
(3700 3200);
DISPLAY 0.872340 (3700 3200);
PAINT GREEN (3700 3200);
DISPLAY INVISIBLE (3700 3200);
FORCEPROP 1 LAST HDL_TAP TRUE
J 0
(4025 3025);
DISPLAY 0.872340 (4025 3025);
DISPLAY INVISIBLE (4025 3025);
FORCEPROP 1 LAST PATH I201
J 0
(3698 3150);
DISPLAY 0.872340 (3698 3150);
PAINT GREEN (3698 3150);
DISPLAY INVISIBLE (3698 3150);
FORCEADD TAP..1
(3900 3100);
FORCEPROP 3 LASTPIN (3850 3100) SIG_NAME P5E_CPU1_PE4_TX_C_DP<13>
J 0
(3860 3110);
DISPLAY 0.659574 (3860 3110);
PAINT MONO (3860 3110);
DISPLAY INVISIBLE (3860 3110);
FORCEPROP 1 LASTPIN (3850 3100) BN 13
J 0
(3838 3108);
DISPLAY 0.680851 (3838 3108);
PAINT GREEN (3838 3108);
FORCEPROP 2 LAST CDS_LIB standard
J 0
(3900 3100);
DISPLAY INVISIBLE (3900 3100);
FORCEPROP 1 LAST BODY_TYPE PLUMBING
J 0
(3900 3150);
DISPLAY 0.872340 (3900 3150);
PAINT GREEN (3900 3150);
DISPLAY INVISIBLE (3900 3150);
FORCEPROP 1 LAST HDL_TAP TRUE
J 0
(4225 2975);
DISPLAY 0.872340 (4225 2975);
DISPLAY INVISIBLE (4225 2975);
FORCEPROP 1 LAST PATH I202
J 0
(3898 3100);
DISPLAY 0.872340 (3898 3100);
PAINT GREEN (3898 3100);
DISPLAY INVISIBLE (3898 3100);
FORCEADD TAP..1
(3700 3350);
FORCEPROP 3 LASTPIN (3650 3350) SIG_NAME P5E_CPU1_PE4_TX_C_DN<14>
J 0
(3660 3360);
DISPLAY 0.659574 (3660 3360);
PAINT MONO (3660 3360);
DISPLAY INVISIBLE (3660 3360);
FORCEPROP 1 LASTPIN (3650 3350) BN 14
J 0
(3638 3358);
DISPLAY 0.680851 (3638 3358);
PAINT GREEN (3638 3358);
FORCEPROP 2 LAST CDS_LIB standard
J 0
(3700 3350);
DISPLAY INVISIBLE (3700 3350);
FORCEPROP 1 LAST BODY_TYPE PLUMBING
J 0
(3700 3400);
DISPLAY 0.872340 (3700 3400);
PAINT GREEN (3700 3400);
DISPLAY INVISIBLE (3700 3400);
FORCEPROP 1 LAST HDL_TAP TRUE
J 0
(4025 3225);
DISPLAY 0.872340 (4025 3225);
DISPLAY INVISIBLE (4025 3225);
FORCEPROP 1 LAST PATH I203
J 0
(3698 3350);
DISPLAY 0.872340 (3698 3350);
PAINT GREEN (3698 3350);
DISPLAY INVISIBLE (3698 3350);
FORCEADD TAP..1
(3900 3300);
FORCEPROP 3 LASTPIN (3850 3300) SIG_NAME P5E_CPU1_PE4_TX_C_DP<14>
J 0
(3860 3310);
DISPLAY 0.659574 (3860 3310);
PAINT MONO (3860 3310);
DISPLAY INVISIBLE (3860 3310);
FORCEPROP 1 LASTPIN (3850 3300) BN 14
J 0
(3838 3308);
DISPLAY 0.680851 (3838 3308);
PAINT GREEN (3838 3308);
FORCEPROP 2 LAST CDS_LIB standard
J 0
(3900 3300);
DISPLAY INVISIBLE (3900 3300);
FORCEPROP 1 LAST BODY_TYPE PLUMBING
J 0
(3900 3350);
DISPLAY 0.872340 (3900 3350);
PAINT GREEN (3900 3350);
DISPLAY INVISIBLE (3900 3350);
FORCEPROP 1 LAST HDL_TAP TRUE
J 0
(4225 3175);
DISPLAY 0.872340 (4225 3175);
DISPLAY INVISIBLE (4225 3175);
FORCEPROP 1 LAST PATH I204
J 0
(3898 3300);
DISPLAY 0.872340 (3898 3300);
PAINT GREEN (3898 3300);
DISPLAY INVISIBLE (3898 3300);
FORCEADD TAP..1
(3900 3500);
FORCEPROP 3 LASTPIN (3850 3500) SIG_NAME P5E_CPU1_PE4_TX_C_DP<15>
J 0
(3860 3510);
DISPLAY 0.659574 (3860 3510);
PAINT MONO (3860 3510);
DISPLAY INVISIBLE (3860 3510);
FORCEPROP 1 LASTPIN (3850 3500) BN 15
J 0
(3838 3508);
DISPLAY 0.680851 (3838 3508);
PAINT GREEN (3838 3508);
FORCEPROP 2 LAST CDS_LIB standard
J 0
(3900 3500);
DISPLAY INVISIBLE (3900 3500);
FORCEPROP 1 LAST BODY_TYPE PLUMBING
J 0
(3900 3550);
DISPLAY 0.872340 (3900 3550);
PAINT GREEN (3900 3550);
DISPLAY INVISIBLE (3900 3550);
FORCEPROP 1 LAST HDL_TAP TRUE
J 0
(4225 3375);
DISPLAY 0.872340 (4225 3375);
DISPLAY INVISIBLE (4225 3375);
FORCEPROP 1 LAST PATH I205
J 0
(3898 3500);
DISPLAY 0.872340 (3898 3500);
PAINT GREEN (3898 3500);
DISPLAY INVISIBLE (3898 3500);
FORCEADD TAP..1
(3700 3550);
FORCEPROP 3 LASTPIN (3650 3550) SIG_NAME P5E_CPU1_PE4_TX_C_DN<15>
J 0
(3660 3560);
DISPLAY 0.659574 (3660 3560);
PAINT MONO (3660 3560);
DISPLAY INVISIBLE (3660 3560);
FORCEPROP 1 LASTPIN (3650 3550) BN 15
J 0
(3638 3558);
DISPLAY 0.680851 (3638 3558);
PAINT GREEN (3638 3558);
FORCEPROP 2 LAST CDS_LIB standard
J 0
(3700 3550);
DISPLAY INVISIBLE (3700 3550);
FORCEPROP 1 LAST BODY_TYPE PLUMBING
J 0
(3700 3600);
DISPLAY 0.872340 (3700 3600);
PAINT GREEN (3700 3600);
DISPLAY INVISIBLE (3700 3600);
FORCEPROP 1 LAST HDL_TAP TRUE
J 0
(4025 3425);
DISPLAY 0.872340 (4025 3425);
DISPLAY INVISIBLE (4025 3425);
FORCEPROP 1 LAST PATH I206
J 0
(3698 3550);
DISPLAY 0.872340 (3698 3550);
PAINT GREEN (3698 3550);
DISPLAY INVISIBLE (3698 3550);
FORCEADD OFFPAGE..2
(4900 3525);
FORCEPROP 2 LAST $XR0 142 
J 0
(5089 3525);
DISPLAY 0.638298 (5089 3525);
PAINT MONO (5089 3525);
FORCEPROP 2 LAST CDS_LIB standard
J 0
(4900 3525);
DISPLAY INVISIBLE (4900 3525);
FORCEPROP 1 LAST OFFPAGE TRUE
J 0
(5225 3400);
DISPLAY 0.872340 (5225 3400);
DISPLAY INVISIBLE (5225 3400);
FORCEPROP 1 LAST COMMENT_BODY TRUE
J 0
(4855 3430);
DISPLAY 0.872340 (4855 3430);
PAINT GREEN (4855 3430);
DISPLAY INVISIBLE (4855 3430);
FORCEPROP 2 LAST PATH I207
J 0
(5075 3600);
DISPLAY 1.021277 (5075 3600);
DISPLAY INVISIBLE (5075 3600);
FORCEADD OFFPAGE..2
(4900 3575);
FORCEPROP 2 LAST $XR0 142 
J 0
(5089 3575);
DISPLAY 0.638298 (5089 3575);
PAINT MONO (5089 3575);
FORCEPROP 2 LAST CDS_LIB standard
J 0
(4900 3575);
DISPLAY INVISIBLE (4900 3575);
FORCEPROP 1 LAST OFFPAGE TRUE
J 0
(5225 3450);
DISPLAY 0.872340 (5225 3450);
DISPLAY INVISIBLE (5225 3450);
FORCEPROP 1 LAST COMMENT_BODY TRUE
J 0
(4855 3480);
DISPLAY 0.872340 (4855 3480);
PAINT GREEN (4855 3480);
DISPLAY INVISIBLE (4855 3480);
FORCEPROP 2 LAST PATH I208
J 0
(5075 3650);
DISPLAY 1.021277 (5075 3650);
DISPLAY INVISIBLE (5075 3650);
FORCEADD OFFPAGE..1
(-3400 1550);
FORCEPROP 2 LAST $XR0 61 
J 0
(-3651 1550);
DISPLAY 0.638298 (-3651 1550);
PAINT MONO (-3651 1550);
FORCEPROP 2 LAST CDS_LIB standard
J 0
(-3400 1550);
DISPLAY INVISIBLE (-3400 1550);
FORCEPROP 1 LAST OFFPAGE TRUE
J 0
(-3075 1425);
DISPLAY 0.872340 (-3075 1425);
DISPLAY INVISIBLE (-3075 1425);
FORCEPROP 1 LAST COMMENT_BODY TRUE
J 0
(-3275 1450);
DISPLAY 0.872340 (-3275 1450);
PAINT GREEN (-3275 1450);
DISPLAY INVISIBLE (-3275 1450);
FORCEPROP 2 LAST PATH I209
J 0
(-3650 1600);
DISPLAY 1.021277 (-3650 1600);
DISPLAY INVISIBLE (-3650 1600);
FORCEADD OFFPAGE..1
(-3400 1600);
FORCEPROP 2 LAST $XR0 61 
J 0
(-3651 1600);
DISPLAY 0.638298 (-3651 1600);
PAINT MONO (-3651 1600);
FORCEPROP 2 LAST CDS_LIB standard
J 0
(-3400 1600);
DISPLAY INVISIBLE (-3400 1600);
FORCEPROP 1 LAST OFFPAGE TRUE
J 0
(-3075 1475);
DISPLAY 0.872340 (-3075 1475);
DISPLAY INVISIBLE (-3075 1475);
FORCEPROP 1 LAST COMMENT_BODY TRUE
J 0
(-3275 1500);
DISPLAY 0.872340 (-3275 1500);
PAINT GREEN (-3275 1500);
DISPLAY INVISIBLE (-3275 1500);
FORCEPROP 2 LAST PATH I210
J 0
(-3650 1650);
DISPLAY 1.021277 (-3650 1650);
DISPLAY INVISIBLE (-3650 1650);
FORCEADD OFFPAGE..1
(-3400 3525);
FORCEPROP 2 LAST $XR0 61 
J 0
(-3651 3525);
DISPLAY 0.638298 (-3651 3525);
PAINT MONO (-3651 3525);
FORCEPROP 2 LAST CDS_LIB standard
J 0
(-3400 3525);
DISPLAY INVISIBLE (-3400 3525);
FORCEPROP 1 LAST OFFPAGE TRUE
J 0
(-3075 3400);
DISPLAY 0.872340 (-3075 3400);
DISPLAY INVISIBLE (-3075 3400);
FORCEPROP 1 LAST COMMENT_BODY TRUE
J 0
(-3275 3425);
DISPLAY 0.872340 (-3275 3425);
PAINT GREEN (-3275 3425);
DISPLAY INVISIBLE (-3275 3425);
FORCEPROP 2 LAST PATH I211
J 0
(-3650 3575);
DISPLAY 1.021277 (-3650 3575);
DISPLAY INVISIBLE (-3650 3575);
FORCEADD OFFPAGE..1
(-3400 3575);
FORCEPROP 2 LAST $XR0 61 
J 0
(-3651 3575);
DISPLAY 0.638298 (-3651 3575);
PAINT MONO (-3651 3575);
FORCEPROP 2 LAST CDS_LIB standard
J 0
(-3400 3575);
DISPLAY INVISIBLE (-3400 3575);
FORCEPROP 1 LAST OFFPAGE TRUE
J 0
(-3075 3450);
DISPLAY 0.872340 (-3075 3450);
DISPLAY INVISIBLE (-3075 3450);
FORCEPROP 1 LAST COMMENT_BODY TRUE
J 0
(-3275 3475);
DISPLAY 0.872340 (-3275 3475);
PAINT GREEN (-3275 3475);
DISPLAY INVISIBLE (-3275 3475);
FORCEPROP 2 LAST PATH I212
J 0
(-3650 3625);
DISPLAY 1.021277 (-3650 3625);
DISPLAY INVISIBLE (-3650 3625);
FORCEADD TAP..1
R 2
(-2450 125);
FORCEPROP 3 LASTPIN (-2400 125) SIG_NAME P5E_CPU1_PE3_TX_DP<0>
J 0
(-2390 135);
DISPLAY 0.659574 (-2390 135);
PAINT MONO (-2390 135);
DISPLAY INVISIBLE (-2390 135);
FORCEPROP 1 LASTPIN (-2400 125) BN 0
J 2
(-2388 133);
DISPLAY 0.680851 (-2388 133);
PAINT GREEN (-2388 133);
FORCEPROP 2 LAST CDS_LIB standard
J 0
(-2450 125);
DISPLAY INVISIBLE (-2450 125);
FORCEPROP 1 LAST BODY_TYPE PLUMBING
J 2
(-2450 175);
DISPLAY 0.872340 (-2450 175);
PAINT GREEN (-2450 175);
DISPLAY INVISIBLE (-2450 175);
FORCEPROP 1 LAST HDL_TAP TRUE
J 2
(-2775 0);
DISPLAY 0.872340 (-2775 0);
DISPLAY INVISIBLE (-2775 0);
FORCEPROP 1 LAST PATH I213
J 2
(-2448 125);
DISPLAY 0.872340 (-2448 125);
PAINT GREEN (-2448 125);
DISPLAY INVISIBLE (-2448 125);
FORCEADD TAP..1
R 2
(-2450 325);
FORCEPROP 3 LASTPIN (-2400 325) SIG_NAME P5E_CPU1_PE3_TX_DP<1>
J 0
(-2390 335);
DISPLAY 0.659574 (-2390 335);
PAINT MONO (-2390 335);
DISPLAY INVISIBLE (-2390 335);
FORCEPROP 1 LASTPIN (-2400 325) BN 1
J 2
(-2388 333);
DISPLAY 0.680851 (-2388 333);
PAINT GREEN (-2388 333);
FORCEPROP 2 LAST CDS_LIB standard
J 0
(-2450 325);
DISPLAY INVISIBLE (-2450 325);
FORCEPROP 1 LAST BODY_TYPE PLUMBING
J 2
(-2450 375);
DISPLAY 0.872340 (-2450 375);
PAINT GREEN (-2450 375);
DISPLAY INVISIBLE (-2450 375);
FORCEPROP 1 LAST HDL_TAP TRUE
J 2
(-2775 200);
DISPLAY 0.872340 (-2775 200);
DISPLAY INVISIBLE (-2775 200);
FORCEPROP 1 LAST PATH I214
J 2
(-2448 325);
DISPLAY 0.872340 (-2448 325);
PAINT GREEN (-2448 325);
DISPLAY INVISIBLE (-2448 325);
FORCEADD TAP..1
R 2
(-2200 175);
FORCEPROP 3 LASTPIN (-2150 175) SIG_NAME P5E_CPU1_PE3_TX_DN<0>
J 0
(-2140 185);
DISPLAY 0.659574 (-2140 185);
PAINT MONO (-2140 185);
DISPLAY INVISIBLE (-2140 185);
FORCEPROP 1 LASTPIN (-2150 175) BN 0
J 2
(-2138 183);
DISPLAY 0.680851 (-2138 183);
PAINT GREEN (-2138 183);
FORCEPROP 2 LAST CDS_LIB standard
J 0
(-2200 175);
DISPLAY INVISIBLE (-2200 175);
FORCEPROP 1 LAST BODY_TYPE PLUMBING
J 2
(-2200 225);
DISPLAY 0.872340 (-2200 225);
PAINT GREEN (-2200 225);
DISPLAY INVISIBLE (-2200 225);
FORCEPROP 1 LAST HDL_TAP TRUE
J 2
(-2525 50);
DISPLAY 0.872340 (-2525 50);
DISPLAY INVISIBLE (-2525 50);
FORCEPROP 1 LAST PATH I215
J 2
(-2198 175);
DISPLAY 0.872340 (-2198 175);
PAINT GREEN (-2198 175);
DISPLAY INVISIBLE (-2198 175);
FORCEADD TAP..1
R 2
(-2200 375);
FORCEPROP 3 LASTPIN (-2150 375) SIG_NAME P5E_CPU1_PE3_TX_DN<1>
J 0
(-2140 385);
DISPLAY 0.659574 (-2140 385);
PAINT MONO (-2140 385);
DISPLAY INVISIBLE (-2140 385);
FORCEPROP 1 LASTPIN (-2150 375) BN 1
J 2
(-2138 383);
DISPLAY 0.680851 (-2138 383);
PAINT GREEN (-2138 383);
FORCEPROP 2 LAST CDS_LIB standard
J 0
(-2200 375);
DISPLAY INVISIBLE (-2200 375);
FORCEPROP 1 LAST BODY_TYPE PLUMBING
J 2
(-2200 425);
DISPLAY 0.872340 (-2200 425);
PAINT GREEN (-2200 425);
DISPLAY INVISIBLE (-2200 425);
FORCEPROP 1 LAST HDL_TAP TRUE
J 2
(-2525 250);
DISPLAY 0.872340 (-2525 250);
DISPLAY INVISIBLE (-2525 250);
FORCEPROP 1 LAST PATH I216
J 2
(-2198 375);
DISPLAY 0.872340 (-2198 375);
PAINT GREEN (-2198 375);
DISPLAY INVISIBLE (-2198 375);
FORCEADD TAP..1
R 2
(-2450 525);
FORCEPROP 3 LASTPIN (-2400 525) SIG_NAME P5E_CPU1_PE3_TX_DP<2>
J 0
(-2390 535);
DISPLAY 0.659574 (-2390 535);
PAINT MONO (-2390 535);
DISPLAY INVISIBLE (-2390 535);
FORCEPROP 1 LASTPIN (-2400 525) BN 2
J 2
(-2388 533);
DISPLAY 0.680851 (-2388 533);
PAINT GREEN (-2388 533);
FORCEPROP 2 LAST CDS_LIB standard
J 0
(-2450 525);
DISPLAY INVISIBLE (-2450 525);
FORCEPROP 1 LAST BODY_TYPE PLUMBING
J 2
(-2450 575);
DISPLAY 0.872340 (-2450 575);
PAINT GREEN (-2450 575);
DISPLAY INVISIBLE (-2450 575);
FORCEPROP 1 LAST HDL_TAP TRUE
J 2
(-2775 400);
DISPLAY 0.872340 (-2775 400);
DISPLAY INVISIBLE (-2775 400);
FORCEPROP 1 LAST PATH I217
J 2
(-2448 525);
DISPLAY 0.872340 (-2448 525);
PAINT GREEN (-2448 525);
DISPLAY INVISIBLE (-2448 525);
FORCEADD TAP..1
R 2
(-2450 725);
FORCEPROP 3 LASTPIN (-2400 725) SIG_NAME P5E_CPU1_PE3_TX_DP<3>
J 0
(-2390 735);
DISPLAY 0.659574 (-2390 735);
PAINT MONO (-2390 735);
DISPLAY INVISIBLE (-2390 735);
FORCEPROP 1 LASTPIN (-2400 725) BN 3
J 2
(-2388 733);
DISPLAY 0.680851 (-2388 733);
PAINT GREEN (-2388 733);
FORCEPROP 2 LAST CDS_LIB standard
J 0
(-2450 725);
DISPLAY INVISIBLE (-2450 725);
FORCEPROP 1 LAST BODY_TYPE PLUMBING
J 2
(-2450 775);
DISPLAY 0.872340 (-2450 775);
PAINT GREEN (-2450 775);
DISPLAY INVISIBLE (-2450 775);
FORCEPROP 1 LAST HDL_TAP TRUE
J 2
(-2775 600);
DISPLAY 0.872340 (-2775 600);
DISPLAY INVISIBLE (-2775 600);
FORCEPROP 1 LAST PATH I218
J 2
(-2448 725);
DISPLAY 0.872340 (-2448 725);
PAINT GREEN (-2448 725);
DISPLAY INVISIBLE (-2448 725);
FORCEADD TAP..1
R 2
(-2450 925);
FORCEPROP 3 LASTPIN (-2400 925) SIG_NAME P5E_CPU1_PE3_TX_DP<4>
J 0
(-2390 935);
DISPLAY 0.659574 (-2390 935);
PAINT MONO (-2390 935);
DISPLAY INVISIBLE (-2390 935);
FORCEPROP 1 LASTPIN (-2400 925) BN 4
J 2
(-2388 933);
DISPLAY 0.680851 (-2388 933);
PAINT GREEN (-2388 933);
FORCEPROP 2 LAST CDS_LIB standard
J 0
(-2450 925);
DISPLAY INVISIBLE (-2450 925);
FORCEPROP 1 LAST BODY_TYPE PLUMBING
J 2
(-2450 975);
DISPLAY 0.872340 (-2450 975);
PAINT GREEN (-2450 975);
DISPLAY INVISIBLE (-2450 975);
FORCEPROP 1 LAST HDL_TAP TRUE
J 2
(-2775 800);
DISPLAY 0.872340 (-2775 800);
DISPLAY INVISIBLE (-2775 800);
FORCEPROP 1 LAST PATH I219
J 2
(-2448 925);
DISPLAY 0.872340 (-2448 925);
PAINT GREEN (-2448 925);
DISPLAY INVISIBLE (-2448 925);
FORCEADD TAP..1
R 2
(-2200 575);
FORCEPROP 3 LASTPIN (-2150 575) SIG_NAME P5E_CPU1_PE3_TX_DN<2>
J 0
(-2140 585);
DISPLAY 0.659574 (-2140 585);
PAINT MONO (-2140 585);
DISPLAY INVISIBLE (-2140 585);
FORCEPROP 1 LASTPIN (-2150 575) BN 2
J 2
(-2138 583);
DISPLAY 0.680851 (-2138 583);
PAINT GREEN (-2138 583);
FORCEPROP 2 LAST CDS_LIB standard
J 0
(-2200 575);
DISPLAY INVISIBLE (-2200 575);
FORCEPROP 1 LAST BODY_TYPE PLUMBING
J 2
(-2200 625);
DISPLAY 0.872340 (-2200 625);
PAINT GREEN (-2200 625);
DISPLAY INVISIBLE (-2200 625);
FORCEPROP 1 LAST HDL_TAP TRUE
J 2
(-2525 450);
DISPLAY 0.872340 (-2525 450);
DISPLAY INVISIBLE (-2525 450);
FORCEPROP 1 LAST PATH I220
J 2
(-2198 575);
DISPLAY 0.872340 (-2198 575);
PAINT GREEN (-2198 575);
DISPLAY INVISIBLE (-2198 575);
FORCEADD TAP..1
R 2
(-2200 775);
FORCEPROP 3 LASTPIN (-2150 775) SIG_NAME P5E_CPU1_PE3_TX_DN<3>
J 0
(-2140 785);
DISPLAY 0.659574 (-2140 785);
PAINT MONO (-2140 785);
DISPLAY INVISIBLE (-2140 785);
FORCEPROP 1 LASTPIN (-2150 775) BN 3
J 2
(-2138 783);
DISPLAY 0.680851 (-2138 783);
PAINT GREEN (-2138 783);
FORCEPROP 2 LAST CDS_LIB standard
J 0
(-2200 775);
DISPLAY INVISIBLE (-2200 775);
FORCEPROP 1 LAST BODY_TYPE PLUMBING
J 2
(-2200 825);
DISPLAY 0.872340 (-2200 825);
PAINT GREEN (-2200 825);
DISPLAY INVISIBLE (-2200 825);
FORCEPROP 1 LAST HDL_TAP TRUE
J 2
(-2525 650);
DISPLAY 0.872340 (-2525 650);
DISPLAY INVISIBLE (-2525 650);
FORCEPROP 1 LAST PATH I221
J 2
(-2198 775);
DISPLAY 0.872340 (-2198 775);
PAINT GREEN (-2198 775);
DISPLAY INVISIBLE (-2198 775);
FORCEADD TAP..1
R 2
(-2200 975);
FORCEPROP 3 LASTPIN (-2150 975) SIG_NAME P5E_CPU1_PE3_TX_DN<4>
J 0
(-2140 985);
DISPLAY 0.659574 (-2140 985);
PAINT MONO (-2140 985);
DISPLAY INVISIBLE (-2140 985);
FORCEPROP 1 LASTPIN (-2150 975) BN 4
J 2
(-2138 983);
DISPLAY 0.680851 (-2138 983);
PAINT GREEN (-2138 983);
FORCEPROP 2 LAST CDS_LIB standard
J 0
(-2200 975);
DISPLAY INVISIBLE (-2200 975);
FORCEPROP 1 LAST BODY_TYPE PLUMBING
J 2
(-2200 1025);
DISPLAY 0.872340 (-2200 1025);
PAINT GREEN (-2200 1025);
DISPLAY INVISIBLE (-2200 1025);
FORCEPROP 1 LAST HDL_TAP TRUE
J 2
(-2525 850);
DISPLAY 0.872340 (-2525 850);
DISPLAY INVISIBLE (-2525 850);
FORCEPROP 1 LAST PATH I222
J 2
(-2198 975);
DISPLAY 0.872340 (-2198 975);
PAINT GREEN (-2198 975);
DISPLAY INVISIBLE (-2198 975);
FORCEADD TAP..1
R 2
(-2450 1125);
FORCEPROP 3 LASTPIN (-2400 1125) SIG_NAME P5E_CPU1_PE3_TX_DP<5>
J 0
(-2390 1135);
DISPLAY 0.659574 (-2390 1135);
PAINT MONO (-2390 1135);
DISPLAY INVISIBLE (-2390 1135);
FORCEPROP 1 LASTPIN (-2400 1125) BN 5
J 2
(-2388 1133);
DISPLAY 0.680851 (-2388 1133);
PAINT GREEN (-2388 1133);
FORCEPROP 2 LAST CDS_LIB standard
J 0
(-2450 1125);
DISPLAY INVISIBLE (-2450 1125);
FORCEPROP 1 LAST BODY_TYPE PLUMBING
J 2
(-2450 1175);
DISPLAY 0.872340 (-2450 1175);
PAINT GREEN (-2450 1175);
DISPLAY INVISIBLE (-2450 1175);
FORCEPROP 1 LAST HDL_TAP TRUE
J 2
(-2775 1000);
DISPLAY 0.872340 (-2775 1000);
DISPLAY INVISIBLE (-2775 1000);
FORCEPROP 1 LAST PATH I223
J 2
(-2448 1125);
DISPLAY 0.872340 (-2448 1125);
PAINT GREEN (-2448 1125);
DISPLAY INVISIBLE (-2448 1125);
FORCEADD TAP..1
R 2
(-2450 1325);
FORCEPROP 3 LASTPIN (-2400 1325) SIG_NAME P5E_CPU1_PE3_TX_DP<6>
J 0
(-2390 1335);
DISPLAY 0.659574 (-2390 1335);
PAINT MONO (-2390 1335);
DISPLAY INVISIBLE (-2390 1335);
FORCEPROP 1 LASTPIN (-2400 1325) BN 6
J 2
(-2388 1333);
DISPLAY 0.680851 (-2388 1333);
PAINT GREEN (-2388 1333);
FORCEPROP 2 LAST CDS_LIB standard
J 0
(-2450 1325);
DISPLAY INVISIBLE (-2450 1325);
FORCEPROP 1 LAST BODY_TYPE PLUMBING
J 2
(-2450 1375);
DISPLAY 0.872340 (-2450 1375);
PAINT GREEN (-2450 1375);
DISPLAY INVISIBLE (-2450 1375);
FORCEPROP 1 LAST HDL_TAP TRUE
J 2
(-2775 1200);
DISPLAY 0.872340 (-2775 1200);
DISPLAY INVISIBLE (-2775 1200);
FORCEPROP 1 LAST PATH I224
J 2
(-2448 1325);
DISPLAY 0.872340 (-2448 1325);
PAINT GREEN (-2448 1325);
DISPLAY INVISIBLE (-2448 1325);
FORCEADD TAP..1
R 2
(-2200 1175);
FORCEPROP 3 LASTPIN (-2150 1175) SIG_NAME P5E_CPU1_PE3_TX_DN<5>
J 0
(-2140 1185);
DISPLAY 0.659574 (-2140 1185);
PAINT MONO (-2140 1185);
DISPLAY INVISIBLE (-2140 1185);
FORCEPROP 1 LASTPIN (-2150 1175) BN 5
J 2
(-2138 1183);
DISPLAY 0.680851 (-2138 1183);
PAINT GREEN (-2138 1183);
FORCEPROP 2 LAST CDS_LIB standard
J 0
(-2200 1175);
DISPLAY INVISIBLE (-2200 1175);
FORCEPROP 1 LAST BODY_TYPE PLUMBING
J 2
(-2200 1225);
DISPLAY 0.872340 (-2200 1225);
PAINT GREEN (-2200 1225);
DISPLAY INVISIBLE (-2200 1225);
FORCEPROP 1 LAST HDL_TAP TRUE
J 2
(-2525 1050);
DISPLAY 0.872340 (-2525 1050);
DISPLAY INVISIBLE (-2525 1050);
FORCEPROP 1 LAST PATH I225
J 2
(-2198 1175);
DISPLAY 0.872340 (-2198 1175);
PAINT GREEN (-2198 1175);
DISPLAY INVISIBLE (-2198 1175);
FORCEADD TAP..1
R 2
(-2200 1375);
FORCEPROP 3 LASTPIN (-2150 1375) SIG_NAME P5E_CPU1_PE3_TX_DN<6>
J 0
(-2140 1385);
DISPLAY 0.659574 (-2140 1385);
PAINT MONO (-2140 1385);
DISPLAY INVISIBLE (-2140 1385);
FORCEPROP 1 LASTPIN (-2150 1375) BN 6
J 2
(-2138 1383);
DISPLAY 0.680851 (-2138 1383);
PAINT GREEN (-2138 1383);
FORCEPROP 2 LAST CDS_LIB standard
J 0
(-2200 1375);
DISPLAY INVISIBLE (-2200 1375);
FORCEPROP 1 LAST BODY_TYPE PLUMBING
J 2
(-2200 1425);
DISPLAY 0.872340 (-2200 1425);
PAINT GREEN (-2200 1425);
DISPLAY INVISIBLE (-2200 1425);
FORCEPROP 1 LAST HDL_TAP TRUE
J 2
(-2525 1250);
DISPLAY 0.872340 (-2525 1250);
DISPLAY INVISIBLE (-2525 1250);
FORCEPROP 1 LAST PATH I226
J 2
(-2198 1375);
DISPLAY 0.872340 (-2198 1375);
PAINT GREEN (-2198 1375);
DISPLAY INVISIBLE (-2198 1375);
FORCEADD TAP..1
R 2
(-2450 1525);
FORCEPROP 3 LASTPIN (-2400 1525) SIG_NAME P5E_CPU1_PE3_TX_DP<7>
J 0
(-2390 1535);
DISPLAY 0.659574 (-2390 1535);
PAINT MONO (-2390 1535);
DISPLAY INVISIBLE (-2390 1535);
FORCEPROP 1 LASTPIN (-2400 1525) BN 7
J 2
(-2388 1533);
DISPLAY 0.680851 (-2388 1533);
PAINT GREEN (-2388 1533);
FORCEPROP 2 LAST CDS_LIB standard
J 0
(-2450 1525);
DISPLAY INVISIBLE (-2450 1525);
FORCEPROP 1 LAST BODY_TYPE PLUMBING
J 2
(-2450 1575);
DISPLAY 0.872340 (-2450 1575);
PAINT GREEN (-2450 1575);
DISPLAY INVISIBLE (-2450 1575);
FORCEPROP 1 LAST HDL_TAP TRUE
J 2
(-2775 1400);
DISPLAY 0.872340 (-2775 1400);
DISPLAY INVISIBLE (-2775 1400);
FORCEPROP 1 LAST PATH I227
J 2
(-2448 1525);
DISPLAY 0.872340 (-2448 1525);
PAINT GREEN (-2448 1525);
DISPLAY INVISIBLE (-2448 1525);
FORCEADD TAP..1
R 2
(-2200 1575);
FORCEPROP 3 LASTPIN (-2150 1575) SIG_NAME P5E_CPU1_PE3_TX_DN<7>
J 0
(-2140 1585);
DISPLAY 0.659574 (-2140 1585);
PAINT MONO (-2140 1585);
DISPLAY INVISIBLE (-2140 1585);
FORCEPROP 1 LASTPIN (-2150 1575) BN 7
J 2
(-2138 1583);
DISPLAY 0.680851 (-2138 1583);
PAINT GREEN (-2138 1583);
FORCEPROP 2 LAST CDS_LIB standard
J 0
(-2200 1575);
DISPLAY INVISIBLE (-2200 1575);
FORCEPROP 1 LAST BODY_TYPE PLUMBING
J 2
(-2200 1625);
DISPLAY 0.872340 (-2200 1625);
PAINT GREEN (-2200 1625);
DISPLAY INVISIBLE (-2200 1625);
FORCEPROP 1 LAST HDL_TAP TRUE
J 2
(-2525 1450);
DISPLAY 0.872340 (-2525 1450);
DISPLAY INVISIBLE (-2525 1450);
FORCEPROP 1 LAST PATH I228
J 2
(-2198 1575);
DISPLAY 0.872340 (-2198 1575);
PAINT GREEN (-2198 1575);
DISPLAY INVISIBLE (-2198 1575);
FORCEADD Q_CAP_DIFFBUS..2
R 2
(-1475 125);
FORCEPROP 1 LAST PART_NUMBER SP_CH4221MEE01
J 2
(-1591 213);
DISPLAY 0.574468 (-1591 213);
PAINT GREEN (-1591 213);
DISPLAY INVISIBLE (-1591 213);
FORCEPROP 2 LAST VALUE DIFF BUS_0.22UF
J 2
(-1625 125);
DISPLAY 0.553191 (-1625 125);
FORCEPROP 1 LAST $LOCATION C1547
J 2
(-1225 150);
DISPLAY 0.723404 (-1225 150);
PAINT GREEN (-1225 150);
FORCEPROP 2 LASTPIN (-1400 125) $PN 1
J 0
(-1390 135);
DISPLAY 0.808511 (-1390 135);
FORCEPROP 2 LASTPIN (-1550 125) $PN 2
J 2
(-1560 135);
DISPLAY 0.808511 (-1560 135);
FORCEPROP 2 LAST TOLERANCE 20%
J 2
(-1550 175);
DISPLAY 0.553191 (-1550 175);
DISPLAY INVISIBLE (-1550 175);
FORCEPROP 2 LAST PACK_TYPE C0201
J 2
(-1650 175);
DISPLAY 0.553191 (-1650 175);
DISPLAY INVISIBLE (-1650 175);
FORCEPROP 1 LAST MATERIAL X6S
J 2
(-1466 204);
DISPLAY 0.574468 (-1466 204);
PAINT GREEN (-1466 204);
DISPLAY INVISIBLE (-1466 204);
FORCEPROP 2 LAST VOLTAGE 6.3V
J 2
(-1825 175);
DISPLAY 0.553191 (-1825 175);
DISPLAY INVISIBLE (-1825 175);
FORCEPROP 1 LAST CDS_LMAN_SYM_OUTLINE -25,50,25,-50
J 2
(-1475 125);
DISPLAY 0.468085 (-1475 125);
PAINT GREEN (-1475 125);
DISPLAY INVISIBLE (-1475 125);
FORCEPROP 2 LAST CDS_LIB pure_quanta
J 2
(-1475 125);
DISPLAY INVISIBLE (-1475 125);
FORCEPROP 1 LAST PIN_NAMES_ROTATE TRUE
J 2
(-1475 125);
DISPLAY 0.489362 (-1475 125);
PAINT GREEN (-1475 125);
DISPLAY INVISIBLE (-1475 125);
FORCEPROP 1 LAST PATH I229
J 2
(-1475 125);
DISPLAY 0.723404 (-1475 125);
DISPLAY INVISIBLE (-1475 125);
FORCEPROP 0 LAST CDS_LOCATION C1547
J 0
(-1225 200);
DISPLAY 1.021277 (-1225 200);
DISPLAY INVISIBLE (-1225 200);
FORCEPROP 2 LAST $SEC 1
J 2
(-1300 200);
DISPLAY 0.680851 (-1300 200);
PAINT MONO (-1300 200);
DISPLAY INVISIBLE (-1300 200);
FORCEPROP 2 LAST CDS_SEC 1
J 2
(-1300 200);
DISPLAY 0.680851 (-1300 200);
DISPLAY INVISIBLE (-1300 200);
FORCEADD Q_CAP_DIFFBUS..2
R 2
(-1475 175);
FORCEPROP 1 LAST PART_NUMBER SP_CH4221MEE01
J 2
(-1591 263);
DISPLAY 0.574468 (-1591 263);
PAINT GREEN (-1591 263);
DISPLAY INVISIBLE (-1591 263);
FORCEPROP 2 LAST VALUE DIFF BUS_0.22UF
J 2
(-1625 175);
DISPLAY 0.553191 (-1625 175);
FORCEPROP 1 LAST $LOCATION C1546
J 2
(-1225 200);
DISPLAY 0.723404 (-1225 200);
PAINT GREEN (-1225 200);
FORCEPROP 2 LASTPIN (-1400 175) $PN 1
J 0
(-1390 185);
DISPLAY 0.808511 (-1390 185);
FORCEPROP 2 LASTPIN (-1550 175) $PN 2
J 2
(-1560 185);
DISPLAY 0.808511 (-1560 185);
FORCEPROP 2 LAST TOLERANCE 20%
J 2
(-1550 225);
DISPLAY 0.553191 (-1550 225);
DISPLAY INVISIBLE (-1550 225);
FORCEPROP 2 LAST PACK_TYPE C0201
J 2
(-1650 225);
DISPLAY 0.553191 (-1650 225);
DISPLAY INVISIBLE (-1650 225);
FORCEPROP 1 LAST MATERIAL X6S
J 2
(-1466 254);
DISPLAY 0.574468 (-1466 254);
PAINT GREEN (-1466 254);
DISPLAY INVISIBLE (-1466 254);
FORCEPROP 2 LAST VOLTAGE 6.3V
J 2
(-1825 225);
DISPLAY 0.553191 (-1825 225);
DISPLAY INVISIBLE (-1825 225);
FORCEPROP 1 LAST CDS_LMAN_SYM_OUTLINE -25,50,25,-50
J 2
(-1475 175);
DISPLAY 0.468085 (-1475 175);
PAINT GREEN (-1475 175);
DISPLAY INVISIBLE (-1475 175);
FORCEPROP 2 LAST CDS_LIB pure_quanta
J 2
(-1475 175);
DISPLAY INVISIBLE (-1475 175);
FORCEPROP 1 LAST PIN_NAMES_ROTATE TRUE
J 2
(-1475 175);
DISPLAY 0.489362 (-1475 175);
PAINT GREEN (-1475 175);
DISPLAY INVISIBLE (-1475 175);
FORCEPROP 1 LAST PATH I230
J 2
(-1475 175);
DISPLAY 0.723404 (-1475 175);
DISPLAY INVISIBLE (-1475 175);
FORCEPROP 0 LAST CDS_LOCATION C1546
J 0
(-1225 250);
DISPLAY 1.021277 (-1225 250);
DISPLAY INVISIBLE (-1225 250);
FORCEPROP 2 LAST $SEC 1
J 2
(-1300 250);
DISPLAY 0.680851 (-1300 250);
PAINT MONO (-1300 250);
DISPLAY INVISIBLE (-1300 250);
FORCEPROP 2 LAST CDS_SEC 1
J 2
(-1300 250);
DISPLAY 0.680851 (-1300 250);
DISPLAY INVISIBLE (-1300 250);
FORCEADD Q_CAP_DIFFBUS..2
R 2
(-1475 325);
FORCEPROP 1 LAST PART_NUMBER SP_CH4221MEE01
J 2
(-1591 413);
DISPLAY 0.574468 (-1591 413);
PAINT GREEN (-1591 413);
DISPLAY INVISIBLE (-1591 413);
FORCEPROP 2 LAST VALUE DIFF BUS_0.22UF
J 2
(-1625 325);
DISPLAY 0.553191 (-1625 325);
FORCEPROP 1 LAST $LOCATION C1545
J 2
(-1225 350);
DISPLAY 0.723404 (-1225 350);
PAINT GREEN (-1225 350);
FORCEPROP 2 LASTPIN (-1400 325) $PN 1
J 0
(-1390 335);
DISPLAY 0.808511 (-1390 335);
FORCEPROP 2 LASTPIN (-1550 325) $PN 2
J 2
(-1560 335);
DISPLAY 0.808511 (-1560 335);
FORCEPROP 2 LAST TOLERANCE 20%
J 2
(-1550 375);
DISPLAY 0.553191 (-1550 375);
DISPLAY INVISIBLE (-1550 375);
FORCEPROP 2 LAST PACK_TYPE C0201
J 2
(-1650 375);
DISPLAY 0.553191 (-1650 375);
DISPLAY INVISIBLE (-1650 375);
FORCEPROP 1 LAST MATERIAL X6S
J 2
(-1466 404);
DISPLAY 0.574468 (-1466 404);
PAINT GREEN (-1466 404);
DISPLAY INVISIBLE (-1466 404);
FORCEPROP 2 LAST VOLTAGE 6.3V
J 2
(-1825 375);
DISPLAY 0.553191 (-1825 375);
DISPLAY INVISIBLE (-1825 375);
FORCEPROP 1 LAST CDS_LMAN_SYM_OUTLINE -25,50,25,-50
J 2
(-1475 325);
DISPLAY 0.468085 (-1475 325);
PAINT GREEN (-1475 325);
DISPLAY INVISIBLE (-1475 325);
FORCEPROP 2 LAST CDS_LIB pure_quanta
J 2
(-1475 325);
DISPLAY INVISIBLE (-1475 325);
FORCEPROP 1 LAST PIN_NAMES_ROTATE TRUE
J 2
(-1475 325);
DISPLAY 0.489362 (-1475 325);
PAINT GREEN (-1475 325);
DISPLAY INVISIBLE (-1475 325);
FORCEPROP 1 LAST PATH I231
J 2
(-1475 325);
DISPLAY 0.723404 (-1475 325);
DISPLAY INVISIBLE (-1475 325);
FORCEPROP 0 LAST CDS_LOCATION C1545
J 0
(-1225 400);
DISPLAY 1.021277 (-1225 400);
DISPLAY INVISIBLE (-1225 400);
FORCEPROP 2 LAST $SEC 1
J 2
(-1300 400);
DISPLAY 0.680851 (-1300 400);
PAINT MONO (-1300 400);
DISPLAY INVISIBLE (-1300 400);
FORCEPROP 2 LAST CDS_SEC 1
J 2
(-1300 400);
DISPLAY 0.680851 (-1300 400);
DISPLAY INVISIBLE (-1300 400);
FORCEADD Q_CAP_DIFFBUS..2
R 2
(-1475 375);
FORCEPROP 1 LAST PART_NUMBER SP_CH4221MEE01
J 2
(-1591 463);
DISPLAY 0.574468 (-1591 463);
PAINT GREEN (-1591 463);
DISPLAY INVISIBLE (-1591 463);
FORCEPROP 2 LAST VALUE DIFF BUS_0.22UF
J 2
(-1625 375);
DISPLAY 0.553191 (-1625 375);
FORCEPROP 1 LAST $LOCATION C1544
J 2
(-1225 400);
DISPLAY 0.723404 (-1225 400);
PAINT GREEN (-1225 400);
FORCEPROP 2 LASTPIN (-1400 375) $PN 1
J 0
(-1390 385);
DISPLAY 0.808511 (-1390 385);
FORCEPROP 2 LASTPIN (-1550 375) $PN 2
J 2
(-1560 385);
DISPLAY 0.808511 (-1560 385);
FORCEPROP 2 LAST TOLERANCE 20%
J 2
(-1550 425);
DISPLAY 0.553191 (-1550 425);
DISPLAY INVISIBLE (-1550 425);
FORCEPROP 2 LAST PACK_TYPE C0201
J 2
(-1650 425);
DISPLAY 0.553191 (-1650 425);
DISPLAY INVISIBLE (-1650 425);
FORCEPROP 1 LAST MATERIAL X6S
J 2
(-1466 454);
DISPLAY 0.574468 (-1466 454);
PAINT GREEN (-1466 454);
DISPLAY INVISIBLE (-1466 454);
FORCEPROP 2 LAST VOLTAGE 6.3V
J 2
(-1825 425);
DISPLAY 0.553191 (-1825 425);
DISPLAY INVISIBLE (-1825 425);
FORCEPROP 2 LAST CDS_LIB pure_quanta
J 2
(-1475 375);
DISPLAY INVISIBLE (-1475 375);
FORCEPROP 1 LAST CDS_LMAN_SYM_OUTLINE -25,50,25,-50
J 2
(-1475 375);
DISPLAY 0.468085 (-1475 375);
PAINT GREEN (-1475 375);
DISPLAY INVISIBLE (-1475 375);
FORCEPROP 1 LAST PIN_NAMES_ROTATE TRUE
J 2
(-1475 375);
DISPLAY 0.489362 (-1475 375);
PAINT GREEN (-1475 375);
DISPLAY INVISIBLE (-1475 375);
FORCEPROP 1 LAST PATH I232
J 2
(-1475 375);
DISPLAY 0.723404 (-1475 375);
DISPLAY INVISIBLE (-1475 375);
FORCEPROP 0 LAST CDS_LOCATION C1544
J 0
(-1225 450);
DISPLAY 1.021277 (-1225 450);
DISPLAY INVISIBLE (-1225 450);
FORCEPROP 2 LAST $SEC 1
J 2
(-1300 450);
DISPLAY 0.680851 (-1300 450);
PAINT MONO (-1300 450);
DISPLAY INVISIBLE (-1300 450);
FORCEPROP 2 LAST CDS_SEC 1
J 2
(-1300 450);
DISPLAY 0.680851 (-1300 450);
DISPLAY INVISIBLE (-1300 450);
FORCEADD Q_CAP_DIFFBUS..2
R 2
(-1475 575);
FORCEPROP 1 LAST PART_NUMBER SP_CH4221MEE01
J 2
(-1591 663);
DISPLAY 0.574468 (-1591 663);
PAINT GREEN (-1591 663);
DISPLAY INVISIBLE (-1591 663);
FORCEPROP 2 LAST VALUE DIFF BUS_0.22UF
J 2
(-1625 575);
DISPLAY 0.553191 (-1625 575);
FORCEPROP 1 LAST $LOCATION C1542
J 2
(-1225 600);
DISPLAY 0.723404 (-1225 600);
PAINT GREEN (-1225 600);
FORCEPROP 2 LASTPIN (-1400 575) $PN 1
J 0
(-1390 585);
DISPLAY 0.808511 (-1390 585);
FORCEPROP 2 LASTPIN (-1550 575) $PN 2
J 2
(-1560 585);
DISPLAY 0.808511 (-1560 585);
FORCEPROP 2 LAST TOLERANCE 20%
J 2
(-1550 625);
DISPLAY 0.553191 (-1550 625);
DISPLAY INVISIBLE (-1550 625);
FORCEPROP 2 LAST PACK_TYPE C0201
J 2
(-1650 625);
DISPLAY 0.553191 (-1650 625);
DISPLAY INVISIBLE (-1650 625);
FORCEPROP 1 LAST MATERIAL X6S
J 2
(-1466 654);
DISPLAY 0.574468 (-1466 654);
PAINT GREEN (-1466 654);
DISPLAY INVISIBLE (-1466 654);
FORCEPROP 2 LAST VOLTAGE 6.3V
J 2
(-1825 625);
DISPLAY 0.553191 (-1825 625);
DISPLAY INVISIBLE (-1825 625);
FORCEPROP 1 LAST CDS_LMAN_SYM_OUTLINE -25,50,25,-50
J 2
(-1475 575);
DISPLAY 0.468085 (-1475 575);
PAINT GREEN (-1475 575);
DISPLAY INVISIBLE (-1475 575);
FORCEPROP 2 LAST CDS_LIB pure_quanta
J 2
(-1475 575);
DISPLAY INVISIBLE (-1475 575);
FORCEPROP 1 LAST PIN_NAMES_ROTATE TRUE
J 2
(-1475 575);
DISPLAY 0.489362 (-1475 575);
PAINT GREEN (-1475 575);
DISPLAY INVISIBLE (-1475 575);
FORCEPROP 1 LAST PATH I233
J 2
(-1475 575);
DISPLAY 0.723404 (-1475 575);
DISPLAY INVISIBLE (-1475 575);
FORCEPROP 0 LAST CDS_LOCATION C1542
J 0
(-1225 650);
DISPLAY 1.021277 (-1225 650);
DISPLAY INVISIBLE (-1225 650);
FORCEPROP 2 LAST $SEC 1
J 2
(-1300 650);
DISPLAY 0.680851 (-1300 650);
PAINT MONO (-1300 650);
DISPLAY INVISIBLE (-1300 650);
FORCEPROP 2 LAST CDS_SEC 1
J 2
(-1300 650);
DISPLAY 0.680851 (-1300 650);
DISPLAY INVISIBLE (-1300 650);
FORCEADD Q_CAP_DIFFBUS..2
R 2
(-1475 525);
FORCEPROP 1 LAST PART_NUMBER SP_CH4221MEE01
J 2
(-1591 613);
DISPLAY 0.574468 (-1591 613);
PAINT GREEN (-1591 613);
DISPLAY INVISIBLE (-1591 613);
FORCEPROP 2 LAST VALUE DIFF BUS_0.22UF
J 2
(-1625 525);
DISPLAY 0.553191 (-1625 525);
FORCEPROP 1 LAST $LOCATION C1543
J 2
(-1225 550);
DISPLAY 0.723404 (-1225 550);
PAINT GREEN (-1225 550);
FORCEPROP 2 LASTPIN (-1400 525) $PN 1
J 0
(-1390 535);
DISPLAY 0.808511 (-1390 535);
FORCEPROP 2 LASTPIN (-1550 525) $PN 2
J 2
(-1560 535);
DISPLAY 0.808511 (-1560 535);
FORCEPROP 2 LAST TOLERANCE 20%
J 2
(-1550 575);
DISPLAY 0.553191 (-1550 575);
DISPLAY INVISIBLE (-1550 575);
FORCEPROP 2 LAST PACK_TYPE C0201
J 2
(-1650 575);
DISPLAY 0.553191 (-1650 575);
DISPLAY INVISIBLE (-1650 575);
FORCEPROP 1 LAST MATERIAL X6S
J 2
(-1466 604);
DISPLAY 0.574468 (-1466 604);
PAINT GREEN (-1466 604);
DISPLAY INVISIBLE (-1466 604);
FORCEPROP 2 LAST VOLTAGE 6.3V
J 2
(-1825 575);
DISPLAY 0.553191 (-1825 575);
DISPLAY INVISIBLE (-1825 575);
FORCEPROP 1 LAST CDS_LMAN_SYM_OUTLINE -25,50,25,-50
J 2
(-1475 525);
DISPLAY 0.468085 (-1475 525);
PAINT GREEN (-1475 525);
DISPLAY INVISIBLE (-1475 525);
FORCEPROP 2 LAST CDS_LIB pure_quanta
J 2
(-1475 525);
DISPLAY INVISIBLE (-1475 525);
FORCEPROP 1 LAST PIN_NAMES_ROTATE TRUE
J 2
(-1475 525);
DISPLAY 0.489362 (-1475 525);
PAINT GREEN (-1475 525);
DISPLAY INVISIBLE (-1475 525);
FORCEPROP 1 LAST PATH I234
J 2
(-1475 525);
DISPLAY 0.723404 (-1475 525);
DISPLAY INVISIBLE (-1475 525);
FORCEPROP 0 LAST CDS_LOCATION C1543
J 0
(-1225 600);
DISPLAY 1.021277 (-1225 600);
DISPLAY INVISIBLE (-1225 600);
FORCEPROP 2 LAST $SEC 1
J 2
(-1300 600);
DISPLAY 0.680851 (-1300 600);
PAINT MONO (-1300 600);
DISPLAY INVISIBLE (-1300 600);
FORCEPROP 2 LAST CDS_SEC 1
J 2
(-1300 600);
DISPLAY 0.680851 (-1300 600);
DISPLAY INVISIBLE (-1300 600);
FORCEADD Q_CAP_DIFFBUS..2
R 2
(-1475 725);
FORCEPROP 1 LAST PART_NUMBER SP_CH4221MEE01
J 2
(-1591 813);
DISPLAY 0.574468 (-1591 813);
PAINT GREEN (-1591 813);
DISPLAY INVISIBLE (-1591 813);
FORCEPROP 2 LAST VALUE DIFF BUS_0.22UF
J 2
(-1625 725);
DISPLAY 0.553191 (-1625 725);
FORCEPROP 1 LAST $LOCATION C1541
J 2
(-1225 750);
DISPLAY 0.723404 (-1225 750);
PAINT GREEN (-1225 750);
FORCEPROP 2 LASTPIN (-1400 725) $PN 1
J 0
(-1390 735);
DISPLAY 0.808511 (-1390 735);
FORCEPROP 2 LASTPIN (-1550 725) $PN 2
J 2
(-1560 735);
DISPLAY 0.808511 (-1560 735);
FORCEPROP 2 LAST TOLERANCE 20%
J 2
(-1550 775);
DISPLAY 0.553191 (-1550 775);
DISPLAY INVISIBLE (-1550 775);
FORCEPROP 2 LAST PACK_TYPE C0201
J 2
(-1650 775);
DISPLAY 0.553191 (-1650 775);
DISPLAY INVISIBLE (-1650 775);
FORCEPROP 1 LAST MATERIAL X6S
J 2
(-1466 804);
DISPLAY 0.574468 (-1466 804);
PAINT GREEN (-1466 804);
DISPLAY INVISIBLE (-1466 804);
FORCEPROP 2 LAST VOLTAGE 6.3V
J 2
(-1825 775);
DISPLAY 0.553191 (-1825 775);
DISPLAY INVISIBLE (-1825 775);
FORCEPROP 2 LAST CDS_LIB pure_quanta
J 2
(-1475 725);
DISPLAY INVISIBLE (-1475 725);
FORCEPROP 1 LAST CDS_LMAN_SYM_OUTLINE -25,50,25,-50
J 2
(-1475 725);
DISPLAY 0.468085 (-1475 725);
PAINT GREEN (-1475 725);
DISPLAY INVISIBLE (-1475 725);
FORCEPROP 1 LAST PIN_NAMES_ROTATE TRUE
J 2
(-1475 725);
DISPLAY 0.489362 (-1475 725);
PAINT GREEN (-1475 725);
DISPLAY INVISIBLE (-1475 725);
FORCEPROP 1 LAST PATH I235
J 2
(-1475 725);
DISPLAY 0.723404 (-1475 725);
DISPLAY INVISIBLE (-1475 725);
FORCEPROP 0 LAST CDS_LOCATION C1541
J 0
(-1225 800);
DISPLAY 1.021277 (-1225 800);
DISPLAY INVISIBLE (-1225 800);
FORCEPROP 2 LAST $SEC 1
J 2
(-1300 800);
DISPLAY 0.680851 (-1300 800);
PAINT MONO (-1300 800);
DISPLAY INVISIBLE (-1300 800);
FORCEPROP 2 LAST CDS_SEC 1
J 2
(-1300 800);
DISPLAY 0.680851 (-1300 800);
DISPLAY INVISIBLE (-1300 800);
FORCEADD Q_CAP_DIFFBUS..2
R 2
(-1475 775);
FORCEPROP 1 LAST PART_NUMBER SP_CH4221MEE01
J 2
(-1591 863);
DISPLAY 0.574468 (-1591 863);
PAINT GREEN (-1591 863);
DISPLAY INVISIBLE (-1591 863);
FORCEPROP 2 LAST VALUE DIFF BUS_0.22UF
J 2
(-1625 775);
DISPLAY 0.553191 (-1625 775);
FORCEPROP 1 LAST $LOCATION C1540
J 2
(-1225 800);
DISPLAY 0.723404 (-1225 800);
PAINT GREEN (-1225 800);
FORCEPROP 2 LASTPIN (-1400 775) $PN 1
J 0
(-1390 785);
DISPLAY 0.808511 (-1390 785);
FORCEPROP 2 LASTPIN (-1550 775) $PN 2
J 2
(-1560 785);
DISPLAY 0.808511 (-1560 785);
FORCEPROP 2 LAST TOLERANCE 20%
J 2
(-1550 825);
DISPLAY 0.553191 (-1550 825);
DISPLAY INVISIBLE (-1550 825);
FORCEPROP 2 LAST PACK_TYPE C0201
J 2
(-1650 825);
DISPLAY 0.553191 (-1650 825);
DISPLAY INVISIBLE (-1650 825);
FORCEPROP 1 LAST MATERIAL X6S
J 2
(-1466 854);
DISPLAY 0.574468 (-1466 854);
PAINT GREEN (-1466 854);
DISPLAY INVISIBLE (-1466 854);
FORCEPROP 2 LAST VOLTAGE 6.3V
J 2
(-1825 825);
DISPLAY 0.553191 (-1825 825);
DISPLAY INVISIBLE (-1825 825);
FORCEPROP 2 LAST CDS_LIB pure_quanta
J 2
(-1475 775);
DISPLAY INVISIBLE (-1475 775);
FORCEPROP 1 LAST CDS_LMAN_SYM_OUTLINE -25,50,25,-50
J 2
(-1475 775);
DISPLAY 0.468085 (-1475 775);
PAINT GREEN (-1475 775);
DISPLAY INVISIBLE (-1475 775);
FORCEPROP 1 LAST PIN_NAMES_ROTATE TRUE
J 2
(-1475 775);
DISPLAY 0.489362 (-1475 775);
PAINT GREEN (-1475 775);
DISPLAY INVISIBLE (-1475 775);
FORCEPROP 1 LAST PATH I236
J 2
(-1475 775);
DISPLAY 0.723404 (-1475 775);
DISPLAY INVISIBLE (-1475 775);
FORCEPROP 0 LAST CDS_LOCATION C1540
J 0
(-1225 850);
DISPLAY 1.021277 (-1225 850);
DISPLAY INVISIBLE (-1225 850);
FORCEPROP 2 LAST $SEC 1
J 2
(-1300 850);
DISPLAY 0.680851 (-1300 850);
PAINT MONO (-1300 850);
DISPLAY INVISIBLE (-1300 850);
FORCEPROP 2 LAST CDS_SEC 1
J 2
(-1300 850);
DISPLAY 0.680851 (-1300 850);
DISPLAY INVISIBLE (-1300 850);
FORCEADD Q_CAP_DIFFBUS..2
R 2
(-1475 925);
FORCEPROP 1 LAST PART_NUMBER SP_CH4221MEE01
J 2
(-1591 1013);
DISPLAY 0.574468 (-1591 1013);
PAINT GREEN (-1591 1013);
DISPLAY INVISIBLE (-1591 1013);
FORCEPROP 2 LAST VALUE DIFF BUS_0.22UF
J 2
(-1625 925);
DISPLAY 0.553191 (-1625 925);
FORCEPROP 1 LAST $LOCATION C1539
J 2
(-1225 950);
DISPLAY 0.723404 (-1225 950);
PAINT GREEN (-1225 950);
FORCEPROP 2 LASTPIN (-1400 925) $PN 1
J 0
(-1390 935);
DISPLAY 0.808511 (-1390 935);
FORCEPROP 2 LASTPIN (-1550 925) $PN 2
J 2
(-1560 935);
DISPLAY 0.808511 (-1560 935);
FORCEPROP 2 LAST TOLERANCE 20%
J 2
(-1550 975);
DISPLAY 0.553191 (-1550 975);
DISPLAY INVISIBLE (-1550 975);
FORCEPROP 2 LAST PACK_TYPE C0201
J 2
(-1650 975);
DISPLAY 0.553191 (-1650 975);
DISPLAY INVISIBLE (-1650 975);
FORCEPROP 1 LAST MATERIAL X6S
J 2
(-1466 1004);
DISPLAY 0.574468 (-1466 1004);
PAINT GREEN (-1466 1004);
DISPLAY INVISIBLE (-1466 1004);
FORCEPROP 2 LAST VOLTAGE 6.3V
J 2
(-1825 975);
DISPLAY 0.553191 (-1825 975);
DISPLAY INVISIBLE (-1825 975);
FORCEPROP 1 LAST CDS_LMAN_SYM_OUTLINE -25,50,25,-50
J 2
(-1475 925);
DISPLAY 0.468085 (-1475 925);
PAINT GREEN (-1475 925);
DISPLAY INVISIBLE (-1475 925);
FORCEPROP 2 LAST CDS_LIB pure_quanta
J 2
(-1475 925);
DISPLAY INVISIBLE (-1475 925);
FORCEPROP 1 LAST PIN_NAMES_ROTATE TRUE
J 2
(-1475 925);
DISPLAY 0.489362 (-1475 925);
PAINT GREEN (-1475 925);
DISPLAY INVISIBLE (-1475 925);
FORCEPROP 1 LAST PATH I237
J 2
(-1475 925);
DISPLAY 0.723404 (-1475 925);
DISPLAY INVISIBLE (-1475 925);
FORCEPROP 0 LAST CDS_LOCATION C1539
J 0
(-1225 1000);
DISPLAY 1.021277 (-1225 1000);
DISPLAY INVISIBLE (-1225 1000);
FORCEPROP 2 LAST $SEC 1
J 2
(-1300 1000);
DISPLAY 0.680851 (-1300 1000);
PAINT MONO (-1300 1000);
DISPLAY INVISIBLE (-1300 1000);
FORCEPROP 2 LAST CDS_SEC 1
J 2
(-1300 1000);
DISPLAY 0.680851 (-1300 1000);
DISPLAY INVISIBLE (-1300 1000);
FORCEADD Q_CAP_DIFFBUS..2
R 2
(-1475 975);
FORCEPROP 1 LAST PART_NUMBER SP_CH4221MEE01
J 2
(-1591 1063);
DISPLAY 0.574468 (-1591 1063);
PAINT GREEN (-1591 1063);
DISPLAY INVISIBLE (-1591 1063);
FORCEPROP 2 LAST VALUE DIFF BUS_0.22UF
J 2
(-1625 975);
DISPLAY 0.553191 (-1625 975);
FORCEPROP 1 LAST $LOCATION C1538
J 2
(-1225 1000);
DISPLAY 0.723404 (-1225 1000);
PAINT GREEN (-1225 1000);
FORCEPROP 2 LASTPIN (-1400 975) $PN 1
J 0
(-1390 985);
DISPLAY 0.808511 (-1390 985);
FORCEPROP 2 LASTPIN (-1550 975) $PN 2
J 2
(-1560 985);
DISPLAY 0.808511 (-1560 985);
FORCEPROP 2 LAST TOLERANCE 20%
J 2
(-1550 1025);
DISPLAY 0.553191 (-1550 1025);
DISPLAY INVISIBLE (-1550 1025);
FORCEPROP 2 LAST PACK_TYPE C0201
J 2
(-1650 1025);
DISPLAY 0.553191 (-1650 1025);
DISPLAY INVISIBLE (-1650 1025);
FORCEPROP 1 LAST MATERIAL X6S
J 2
(-1466 1054);
DISPLAY 0.574468 (-1466 1054);
PAINT GREEN (-1466 1054);
DISPLAY INVISIBLE (-1466 1054);
FORCEPROP 2 LAST VOLTAGE 6.3V
J 2
(-1825 1025);
DISPLAY 0.553191 (-1825 1025);
DISPLAY INVISIBLE (-1825 1025);
FORCEPROP 1 LAST CDS_LMAN_SYM_OUTLINE -25,50,25,-50
J 2
(-1475 975);
DISPLAY 0.468085 (-1475 975);
PAINT GREEN (-1475 975);
DISPLAY INVISIBLE (-1475 975);
FORCEPROP 2 LAST CDS_LIB pure_quanta
J 2
(-1475 975);
DISPLAY INVISIBLE (-1475 975);
FORCEPROP 1 LAST PIN_NAMES_ROTATE TRUE
J 2
(-1475 975);
DISPLAY 0.489362 (-1475 975);
PAINT GREEN (-1475 975);
DISPLAY INVISIBLE (-1475 975);
FORCEPROP 1 LAST PATH I238
J 2
(-1475 975);
DISPLAY 0.723404 (-1475 975);
DISPLAY INVISIBLE (-1475 975);
FORCEPROP 0 LAST CDS_LOCATION C1538
J 0
(-1225 1050);
DISPLAY 1.021277 (-1225 1050);
DISPLAY INVISIBLE (-1225 1050);
FORCEPROP 2 LAST $SEC 1
J 2
(-1300 1050);
DISPLAY 0.680851 (-1300 1050);
PAINT MONO (-1300 1050);
DISPLAY INVISIBLE (-1300 1050);
FORCEPROP 2 LAST CDS_SEC 1
J 2
(-1300 1050);
DISPLAY 0.680851 (-1300 1050);
DISPLAY INVISIBLE (-1300 1050);
FORCEADD TAP..1
(-925 175);
FORCEPROP 3 LASTPIN (-975 175) SIG_NAME P5E_CPU1_PE3_TX_C_DN<0>
J 0
(-965 185);
DISPLAY 0.659574 (-965 185);
PAINT MONO (-965 185);
DISPLAY INVISIBLE (-965 185);
FORCEPROP 1 LASTPIN (-975 175) BN 0
J 0
(-987 183);
DISPLAY 0.680851 (-987 183);
PAINT GREEN (-987 183);
FORCEPROP 2 LAST CDS_LIB standard
J 0
(-925 175);
DISPLAY INVISIBLE (-925 175);
FORCEPROP 1 LAST BODY_TYPE PLUMBING
J 0
(-925 225);
DISPLAY 0.872340 (-925 225);
PAINT GREEN (-925 225);
DISPLAY INVISIBLE (-925 225);
FORCEPROP 1 LAST HDL_TAP TRUE
J 0
(-600 50);
DISPLAY 0.872340 (-600 50);
DISPLAY INVISIBLE (-600 50);
FORCEPROP 1 LAST PATH I239
J 0
(-927 175);
DISPLAY 0.872340 (-927 175);
PAINT GREEN (-927 175);
DISPLAY INVISIBLE (-927 175);
FORCEADD TAP..1
(-925 375);
FORCEPROP 3 LASTPIN (-975 375) SIG_NAME P5E_CPU1_PE3_TX_C_DN<1>
J 0
(-965 385);
DISPLAY 0.659574 (-965 385);
PAINT MONO (-965 385);
DISPLAY INVISIBLE (-965 385);
FORCEPROP 1 LASTPIN (-975 375) BN 1
J 0
(-987 383);
DISPLAY 0.680851 (-987 383);
PAINT GREEN (-987 383);
FORCEPROP 2 LAST CDS_LIB standard
J 0
(-925 375);
DISPLAY INVISIBLE (-925 375);
FORCEPROP 1 LAST BODY_TYPE PLUMBING
J 0
(-925 425);
DISPLAY 0.872340 (-925 425);
PAINT GREEN (-925 425);
DISPLAY INVISIBLE (-925 425);
FORCEPROP 1 LAST HDL_TAP TRUE
J 0
(-600 250);
DISPLAY 0.872340 (-600 250);
DISPLAY INVISIBLE (-600 250);
FORCEPROP 1 LAST PATH I240
J 0
(-927 375);
DISPLAY 0.872340 (-927 375);
PAINT GREEN (-927 375);
DISPLAY INVISIBLE (-927 375);
FORCEADD TAP..1
(-725 125);
FORCEPROP 3 LASTPIN (-775 125) SIG_NAME P5E_CPU1_PE3_TX_C_DP<0>
J 0
(-765 135);
DISPLAY 0.659574 (-765 135);
PAINT MONO (-765 135);
DISPLAY INVISIBLE (-765 135);
FORCEPROP 1 LASTPIN (-775 125) BN 0
J 0
(-787 133);
DISPLAY 0.680851 (-787 133);
PAINT GREEN (-787 133);
FORCEPROP 2 LAST CDS_LIB standard
J 0
(-725 125);
DISPLAY INVISIBLE (-725 125);
FORCEPROP 1 LAST BODY_TYPE PLUMBING
J 0
(-725 175);
DISPLAY 0.872340 (-725 175);
PAINT GREEN (-725 175);
DISPLAY INVISIBLE (-725 175);
FORCEPROP 1 LAST HDL_TAP TRUE
J 0
(-400 0);
DISPLAY 0.872340 (-400 0);
DISPLAY INVISIBLE (-400 0);
FORCEPROP 1 LAST PATH I241
J 0
(-727 125);
DISPLAY 0.872340 (-727 125);
PAINT GREEN (-727 125);
DISPLAY INVISIBLE (-727 125);
FORCEADD TAP..1
(-725 325);
FORCEPROP 3 LASTPIN (-775 325) SIG_NAME P5E_CPU1_PE3_TX_C_DP<1>
J 0
(-765 335);
DISPLAY 0.659574 (-765 335);
PAINT MONO (-765 335);
DISPLAY INVISIBLE (-765 335);
FORCEPROP 1 LASTPIN (-775 325) BN 1
J 0
(-787 333);
DISPLAY 0.680851 (-787 333);
PAINT GREEN (-787 333);
FORCEPROP 2 LAST CDS_LIB standard
J 0
(-725 325);
DISPLAY INVISIBLE (-725 325);
FORCEPROP 1 LAST BODY_TYPE PLUMBING
J 0
(-725 375);
DISPLAY 0.872340 (-725 375);
PAINT GREEN (-725 375);
DISPLAY INVISIBLE (-725 375);
FORCEPROP 1 LAST HDL_TAP TRUE
J 0
(-400 200);
DISPLAY 0.872340 (-400 200);
DISPLAY INVISIBLE (-400 200);
FORCEPROP 1 LAST PATH I242
J 0
(-727 325);
DISPLAY 0.872340 (-727 325);
PAINT GREEN (-727 325);
DISPLAY INVISIBLE (-727 325);
FORCEADD TAP..1
(-925 575);
FORCEPROP 3 LASTPIN (-975 575) SIG_NAME P5E_CPU1_PE3_TX_C_DN<2>
J 0
(-965 585);
DISPLAY 0.659574 (-965 585);
PAINT MONO (-965 585);
DISPLAY INVISIBLE (-965 585);
FORCEPROP 1 LASTPIN (-975 575) BN 2
J 0
(-987 583);
DISPLAY 0.680851 (-987 583);
PAINT GREEN (-987 583);
FORCEPROP 2 LAST CDS_LIB standard
J 0
(-925 575);
DISPLAY INVISIBLE (-925 575);
FORCEPROP 1 LAST BODY_TYPE PLUMBING
J 0
(-925 625);
DISPLAY 0.872340 (-925 625);
PAINT GREEN (-925 625);
DISPLAY INVISIBLE (-925 625);
FORCEPROP 1 LAST HDL_TAP TRUE
J 0
(-600 450);
DISPLAY 0.872340 (-600 450);
DISPLAY INVISIBLE (-600 450);
FORCEPROP 1 LAST PATH I243
J 0
(-927 575);
DISPLAY 0.872340 (-927 575);
PAINT GREEN (-927 575);
DISPLAY INVISIBLE (-927 575);
FORCEADD TAP..1
(-925 975);
FORCEPROP 3 LASTPIN (-975 975) SIG_NAME P5E_CPU1_PE3_TX_C_DN<4>
J 0
(-965 985);
DISPLAY 0.659574 (-965 985);
PAINT MONO (-965 985);
DISPLAY INVISIBLE (-965 985);
FORCEPROP 1 LASTPIN (-975 975) BN 4
J 0
(-987 983);
DISPLAY 0.680851 (-987 983);
PAINT GREEN (-987 983);
FORCEPROP 2 LAST CDS_LIB standard
J 0
(-925 975);
DISPLAY INVISIBLE (-925 975);
FORCEPROP 1 LAST BODY_TYPE PLUMBING
J 0
(-925 1025);
DISPLAY 0.872340 (-925 1025);
PAINT GREEN (-925 1025);
DISPLAY INVISIBLE (-925 1025);
FORCEPROP 1 LAST HDL_TAP TRUE
J 0
(-600 850);
DISPLAY 0.872340 (-600 850);
DISPLAY INVISIBLE (-600 850);
FORCEPROP 1 LAST PATH I244
J 0
(-927 975);
DISPLAY 0.872340 (-927 975);
PAINT GREEN (-927 975);
DISPLAY INVISIBLE (-927 975);
FORCEADD TAP..1
(-925 775);
FORCEPROP 3 LASTPIN (-975 775) SIG_NAME P5E_CPU1_PE3_TX_C_DN<3>
J 0
(-965 785);
DISPLAY 0.659574 (-965 785);
PAINT MONO (-965 785);
DISPLAY INVISIBLE (-965 785);
FORCEPROP 1 LASTPIN (-975 775) BN 3
J 0
(-987 783);
DISPLAY 0.680851 (-987 783);
PAINT GREEN (-987 783);
FORCEPROP 2 LAST CDS_LIB standard
J 0
(-925 775);
DISPLAY INVISIBLE (-925 775);
FORCEPROP 1 LAST BODY_TYPE PLUMBING
J 0
(-925 825);
DISPLAY 0.872340 (-925 825);
PAINT GREEN (-925 825);
DISPLAY INVISIBLE (-925 825);
FORCEPROP 1 LAST HDL_TAP TRUE
J 0
(-600 650);
DISPLAY 0.872340 (-600 650);
DISPLAY INVISIBLE (-600 650);
FORCEPROP 1 LAST PATH I245
J 0
(-927 775);
DISPLAY 0.872340 (-927 775);
PAINT GREEN (-927 775);
DISPLAY INVISIBLE (-927 775);
FORCEADD TAP..1
(-725 725);
FORCEPROP 3 LASTPIN (-775 725) SIG_NAME P5E_CPU1_PE3_TX_C_DP<3>
J 0
(-765 735);
DISPLAY 0.659574 (-765 735);
PAINT MONO (-765 735);
DISPLAY INVISIBLE (-765 735);
FORCEPROP 1 LASTPIN (-775 725) BN 3
J 0
(-787 733);
DISPLAY 0.680851 (-787 733);
PAINT GREEN (-787 733);
FORCEPROP 2 LAST CDS_LIB standard
J 0
(-725 725);
DISPLAY INVISIBLE (-725 725);
FORCEPROP 1 LAST BODY_TYPE PLUMBING
J 0
(-725 775);
DISPLAY 0.872340 (-725 775);
PAINT GREEN (-725 775);
DISPLAY INVISIBLE (-725 775);
FORCEPROP 1 LAST HDL_TAP TRUE
J 0
(-400 600);
DISPLAY 0.872340 (-400 600);
DISPLAY INVISIBLE (-400 600);
FORCEPROP 1 LAST PATH I246
J 0
(-727 725);
DISPLAY 0.872340 (-727 725);
PAINT GREEN (-727 725);
DISPLAY INVISIBLE (-727 725);
FORCEADD TAP..1
(-725 525);
FORCEPROP 3 LASTPIN (-775 525) SIG_NAME P5E_CPU1_PE3_TX_C_DP<2>
J 0
(-765 535);
DISPLAY 0.659574 (-765 535);
PAINT MONO (-765 535);
DISPLAY INVISIBLE (-765 535);
FORCEPROP 1 LASTPIN (-775 525) BN 2
J 0
(-787 533);
DISPLAY 0.680851 (-787 533);
PAINT GREEN (-787 533);
FORCEPROP 2 LAST CDS_LIB standard
J 0
(-725 525);
DISPLAY INVISIBLE (-725 525);
FORCEPROP 1 LAST BODY_TYPE PLUMBING
J 0
(-725 575);
DISPLAY 0.872340 (-725 575);
PAINT GREEN (-725 575);
DISPLAY INVISIBLE (-725 575);
FORCEPROP 1 LAST HDL_TAP TRUE
J 0
(-400 400);
DISPLAY 0.872340 (-400 400);
DISPLAY INVISIBLE (-400 400);
FORCEPROP 1 LAST PATH I247
J 0
(-727 525);
DISPLAY 0.872340 (-727 525);
PAINT GREEN (-727 525);
DISPLAY INVISIBLE (-727 525);
FORCEADD TAP..1
(-725 925);
FORCEPROP 3 LASTPIN (-775 925) SIG_NAME P5E_CPU1_PE3_TX_C_DP<4>
J 0
(-765 935);
DISPLAY 0.659574 (-765 935);
PAINT MONO (-765 935);
DISPLAY INVISIBLE (-765 935);
FORCEPROP 1 LASTPIN (-775 925) BN 4
J 0
(-787 933);
DISPLAY 0.680851 (-787 933);
PAINT GREEN (-787 933);
FORCEPROP 2 LAST CDS_LIB standard
J 0
(-725 925);
DISPLAY INVISIBLE (-725 925);
FORCEPROP 1 LAST BODY_TYPE PLUMBING
J 0
(-725 975);
DISPLAY 0.872340 (-725 975);
PAINT GREEN (-725 975);
DISPLAY INVISIBLE (-725 975);
FORCEPROP 1 LAST HDL_TAP TRUE
J 0
(-400 800);
DISPLAY 0.872340 (-400 800);
DISPLAY INVISIBLE (-400 800);
FORCEPROP 1 LAST PATH I248
J 0
(-727 925);
DISPLAY 0.872340 (-727 925);
PAINT GREEN (-727 925);
DISPLAY INVISIBLE (-727 925);
FORCEADD Q_CAP_DIFFBUS..2
R 2
(-1475 1125);
FORCEPROP 1 LAST PART_NUMBER SP_CH4221MEE01
J 2
(-1591 1213);
DISPLAY 0.574468 (-1591 1213);
PAINT GREEN (-1591 1213);
DISPLAY INVISIBLE (-1591 1213);
FORCEPROP 2 LAST VALUE DIFF BUS_0.22UF
J 2
(-1625 1125);
DISPLAY 0.553191 (-1625 1125);
FORCEPROP 1 LAST $LOCATION C1537
J 2
(-1225 1150);
DISPLAY 0.723404 (-1225 1150);
PAINT GREEN (-1225 1150);
FORCEPROP 2 LASTPIN (-1400 1125) $PN 1
J 0
(-1390 1135);
DISPLAY 0.808511 (-1390 1135);
FORCEPROP 2 LASTPIN (-1550 1125) $PN 2
J 2
(-1560 1135);
DISPLAY 0.808511 (-1560 1135);
FORCEPROP 2 LAST TOLERANCE 20%
J 2
(-1550 1175);
DISPLAY 0.553191 (-1550 1175);
DISPLAY INVISIBLE (-1550 1175);
FORCEPROP 2 LAST PACK_TYPE C0201
J 2
(-1650 1175);
DISPLAY 0.553191 (-1650 1175);
DISPLAY INVISIBLE (-1650 1175);
FORCEPROP 1 LAST MATERIAL X6S
J 2
(-1466 1204);
DISPLAY 0.574468 (-1466 1204);
PAINT GREEN (-1466 1204);
DISPLAY INVISIBLE (-1466 1204);
FORCEPROP 2 LAST VOLTAGE 6.3V
J 2
(-1825 1175);
DISPLAY 0.553191 (-1825 1175);
DISPLAY INVISIBLE (-1825 1175);
FORCEPROP 1 LAST CDS_LMAN_SYM_OUTLINE -25,50,25,-50
J 2
(-1475 1125);
DISPLAY 0.468085 (-1475 1125);
PAINT GREEN (-1475 1125);
DISPLAY INVISIBLE (-1475 1125);
FORCEPROP 2 LAST CDS_LIB pure_quanta
J 2
(-1475 1125);
DISPLAY INVISIBLE (-1475 1125);
FORCEPROP 1 LAST PIN_NAMES_ROTATE TRUE
J 2
(-1475 1125);
DISPLAY 0.489362 (-1475 1125);
PAINT GREEN (-1475 1125);
DISPLAY INVISIBLE (-1475 1125);
FORCEPROP 1 LAST PATH I249
J 2
(-1475 1125);
DISPLAY 0.723404 (-1475 1125);
DISPLAY INVISIBLE (-1475 1125);
FORCEPROP 0 LAST CDS_LOCATION C1537
J 0
(-1225 1200);
DISPLAY 1.021277 (-1225 1200);
DISPLAY INVISIBLE (-1225 1200);
FORCEPROP 2 LAST $SEC 1
J 2
(-1300 1200);
DISPLAY 0.680851 (-1300 1200);
PAINT MONO (-1300 1200);
DISPLAY INVISIBLE (-1300 1200);
FORCEPROP 2 LAST CDS_SEC 1
J 2
(-1300 1200);
DISPLAY 0.680851 (-1300 1200);
DISPLAY INVISIBLE (-1300 1200);
FORCEADD Q_CAP_DIFFBUS..2
R 2
(-1475 1175);
FORCEPROP 1 LAST PART_NUMBER SP_CH4221MEE01
J 2
(-1591 1263);
DISPLAY 0.574468 (-1591 1263);
PAINT GREEN (-1591 1263);
DISPLAY INVISIBLE (-1591 1263);
FORCEPROP 2 LAST VALUE DIFF BUS_0.22UF
J 2
(-1625 1175);
DISPLAY 0.553191 (-1625 1175);
FORCEPROP 1 LAST $LOCATION C1536
J 2
(-1225 1200);
DISPLAY 0.723404 (-1225 1200);
PAINT GREEN (-1225 1200);
FORCEPROP 2 LASTPIN (-1400 1175) $PN 1
J 0
(-1390 1185);
DISPLAY 0.808511 (-1390 1185);
FORCEPROP 2 LASTPIN (-1550 1175) $PN 2
J 2
(-1560 1185);
DISPLAY 0.808511 (-1560 1185);
FORCEPROP 2 LAST TOLERANCE 20%
J 2
(-1550 1225);
DISPLAY 0.553191 (-1550 1225);
DISPLAY INVISIBLE (-1550 1225);
FORCEPROP 2 LAST PACK_TYPE C0201
J 2
(-1650 1225);
DISPLAY 0.553191 (-1650 1225);
DISPLAY INVISIBLE (-1650 1225);
FORCEPROP 1 LAST MATERIAL X6S
J 2
(-1466 1254);
DISPLAY 0.574468 (-1466 1254);
PAINT GREEN (-1466 1254);
DISPLAY INVISIBLE (-1466 1254);
FORCEPROP 2 LAST VOLTAGE 6.3V
J 2
(-1825 1225);
DISPLAY 0.553191 (-1825 1225);
DISPLAY INVISIBLE (-1825 1225);
FORCEPROP 1 LAST CDS_LMAN_SYM_OUTLINE -25,50,25,-50
J 2
(-1475 1175);
DISPLAY 0.468085 (-1475 1175);
PAINT GREEN (-1475 1175);
DISPLAY INVISIBLE (-1475 1175);
FORCEPROP 2 LAST CDS_LIB pure_quanta
J 2
(-1475 1175);
DISPLAY INVISIBLE (-1475 1175);
FORCEPROP 1 LAST PIN_NAMES_ROTATE TRUE
J 2
(-1475 1175);
DISPLAY 0.489362 (-1475 1175);
PAINT GREEN (-1475 1175);
DISPLAY INVISIBLE (-1475 1175);
FORCEPROP 1 LAST PATH I250
J 2
(-1475 1175);
DISPLAY 0.723404 (-1475 1175);
DISPLAY INVISIBLE (-1475 1175);
FORCEPROP 0 LAST CDS_LOCATION C1536
J 0
(-1225 1250);
DISPLAY 1.021277 (-1225 1250);
DISPLAY INVISIBLE (-1225 1250);
FORCEPROP 2 LAST $SEC 1
J 2
(-1300 1250);
DISPLAY 0.680851 (-1300 1250);
PAINT MONO (-1300 1250);
DISPLAY INVISIBLE (-1300 1250);
FORCEPROP 2 LAST CDS_SEC 1
J 2
(-1300 1250);
DISPLAY 0.680851 (-1300 1250);
DISPLAY INVISIBLE (-1300 1250);
FORCEADD Q_CAP_DIFFBUS..2
R 2
(-1475 1375);
FORCEPROP 1 LAST PART_NUMBER SP_CH4221MEE01
J 2
(-1591 1463);
DISPLAY 0.574468 (-1591 1463);
PAINT GREEN (-1591 1463);
DISPLAY INVISIBLE (-1591 1463);
FORCEPROP 2 LAST VALUE DIFF BUS_0.22UF
J 2
(-1625 1375);
DISPLAY 0.553191 (-1625 1375);
FORCEPROP 1 LAST $LOCATION C1534
J 2
(-1225 1400);
DISPLAY 0.723404 (-1225 1400);
PAINT GREEN (-1225 1400);
FORCEPROP 2 LASTPIN (-1400 1375) $PN 1
J 0
(-1390 1385);
DISPLAY 0.808511 (-1390 1385);
FORCEPROP 2 LASTPIN (-1550 1375) $PN 2
J 2
(-1560 1385);
DISPLAY 0.808511 (-1560 1385);
FORCEPROP 2 LAST TOLERANCE 20%
J 2
(-1550 1425);
DISPLAY 0.553191 (-1550 1425);
DISPLAY INVISIBLE (-1550 1425);
FORCEPROP 2 LAST PACK_TYPE C0201
J 2
(-1650 1425);
DISPLAY 0.553191 (-1650 1425);
DISPLAY INVISIBLE (-1650 1425);
FORCEPROP 1 LAST MATERIAL X6S
J 2
(-1466 1454);
DISPLAY 0.574468 (-1466 1454);
PAINT GREEN (-1466 1454);
DISPLAY INVISIBLE (-1466 1454);
FORCEPROP 2 LAST VOLTAGE 6.3V
J 2
(-1825 1425);
DISPLAY 0.553191 (-1825 1425);
DISPLAY INVISIBLE (-1825 1425);
FORCEPROP 1 LAST CDS_LMAN_SYM_OUTLINE -25,50,25,-50
J 2
(-1475 1375);
DISPLAY 0.468085 (-1475 1375);
PAINT GREEN (-1475 1375);
DISPLAY INVISIBLE (-1475 1375);
FORCEPROP 2 LAST CDS_LIB pure_quanta
J 2
(-1475 1375);
DISPLAY INVISIBLE (-1475 1375);
FORCEPROP 1 LAST PIN_NAMES_ROTATE TRUE
J 2
(-1475 1375);
DISPLAY 0.489362 (-1475 1375);
PAINT GREEN (-1475 1375);
DISPLAY INVISIBLE (-1475 1375);
FORCEPROP 1 LAST PATH I251
J 2
(-1475 1375);
DISPLAY 0.723404 (-1475 1375);
DISPLAY INVISIBLE (-1475 1375);
FORCEPROP 0 LAST CDS_LOCATION C1534
J 0
(-1225 1450);
DISPLAY 1.021277 (-1225 1450);
DISPLAY INVISIBLE (-1225 1450);
FORCEPROP 2 LAST $SEC 1
J 2
(-1300 1450);
DISPLAY 0.680851 (-1300 1450);
PAINT MONO (-1300 1450);
DISPLAY INVISIBLE (-1300 1450);
FORCEPROP 2 LAST CDS_SEC 1
J 2
(-1300 1450);
DISPLAY 0.680851 (-1300 1450);
DISPLAY INVISIBLE (-1300 1450);
FORCEADD Q_CAP_DIFFBUS..2
R 2
(-1475 1325);
FORCEPROP 1 LAST PART_NUMBER SP_CH4221MEE01
J 2
(-1591 1413);
DISPLAY 0.574468 (-1591 1413);
PAINT GREEN (-1591 1413);
DISPLAY INVISIBLE (-1591 1413);
FORCEPROP 2 LAST VALUE DIFF BUS_0.22UF
J 2
(-1625 1325);
DISPLAY 0.553191 (-1625 1325);
FORCEPROP 1 LAST $LOCATION C1535
J 2
(-1225 1350);
DISPLAY 0.723404 (-1225 1350);
PAINT GREEN (-1225 1350);
FORCEPROP 2 LASTPIN (-1400 1325) $PN 1
J 0
(-1390 1335);
DISPLAY 0.808511 (-1390 1335);
FORCEPROP 2 LASTPIN (-1550 1325) $PN 2
J 2
(-1560 1335);
DISPLAY 0.808511 (-1560 1335);
FORCEPROP 2 LAST TOLERANCE 20%
J 2
(-1550 1375);
DISPLAY 0.553191 (-1550 1375);
DISPLAY INVISIBLE (-1550 1375);
FORCEPROP 2 LAST PACK_TYPE C0201
J 2
(-1650 1375);
DISPLAY 0.553191 (-1650 1375);
DISPLAY INVISIBLE (-1650 1375);
FORCEPROP 1 LAST MATERIAL X6S
J 2
(-1466 1404);
DISPLAY 0.574468 (-1466 1404);
PAINT GREEN (-1466 1404);
DISPLAY INVISIBLE (-1466 1404);
FORCEPROP 2 LAST VOLTAGE 6.3V
J 2
(-1825 1375);
DISPLAY 0.553191 (-1825 1375);
DISPLAY INVISIBLE (-1825 1375);
FORCEPROP 1 LAST CDS_LMAN_SYM_OUTLINE -25,50,25,-50
J 2
(-1475 1325);
DISPLAY 0.468085 (-1475 1325);
PAINT GREEN (-1475 1325);
DISPLAY INVISIBLE (-1475 1325);
FORCEPROP 2 LAST CDS_LIB pure_quanta
J 2
(-1475 1325);
DISPLAY INVISIBLE (-1475 1325);
FORCEPROP 1 LAST PIN_NAMES_ROTATE TRUE
J 2
(-1475 1325);
DISPLAY 0.489362 (-1475 1325);
PAINT GREEN (-1475 1325);
DISPLAY INVISIBLE (-1475 1325);
FORCEPROP 1 LAST PATH I252
J 2
(-1475 1325);
DISPLAY 0.723404 (-1475 1325);
DISPLAY INVISIBLE (-1475 1325);
FORCEPROP 0 LAST CDS_LOCATION C1535
J 0
(-1225 1400);
DISPLAY 1.021277 (-1225 1400);
DISPLAY INVISIBLE (-1225 1400);
FORCEPROP 2 LAST $SEC 1
J 2
(-1300 1400);
DISPLAY 0.680851 (-1300 1400);
PAINT MONO (-1300 1400);
DISPLAY INVISIBLE (-1300 1400);
FORCEPROP 2 LAST CDS_SEC 1
J 2
(-1300 1400);
DISPLAY 0.680851 (-1300 1400);
DISPLAY INVISIBLE (-1300 1400);
FORCEADD Q_CAP_DIFFBUS..2
R 2
(-1475 1525);
FORCEPROP 1 LAST PART_NUMBER SP_CH4221MEE01
J 2
(-1591 1613);
DISPLAY 0.574468 (-1591 1613);
PAINT GREEN (-1591 1613);
DISPLAY INVISIBLE (-1591 1613);
FORCEPROP 2 LAST VALUE DIFF BUS_0.22UF
J 2
(-1625 1525);
DISPLAY 0.553191 (-1625 1525);
FORCEPROP 1 LAST $LOCATION C1533
J 2
(-1225 1550);
DISPLAY 0.723404 (-1225 1550);
PAINT GREEN (-1225 1550);
FORCEPROP 2 LASTPIN (-1400 1525) $PN 1
J 0
(-1390 1535);
DISPLAY 0.808511 (-1390 1535);
FORCEPROP 2 LASTPIN (-1550 1525) $PN 2
J 2
(-1560 1535);
DISPLAY 0.808511 (-1560 1535);
FORCEPROP 2 LAST TOLERANCE 20%
J 2
(-1550 1575);
DISPLAY 0.553191 (-1550 1575);
DISPLAY INVISIBLE (-1550 1575);
FORCEPROP 2 LAST PACK_TYPE C0201
J 2
(-1650 1575);
DISPLAY 0.553191 (-1650 1575);
DISPLAY INVISIBLE (-1650 1575);
FORCEPROP 1 LAST MATERIAL X6S
J 2
(-1466 1604);
DISPLAY 0.574468 (-1466 1604);
PAINT GREEN (-1466 1604);
DISPLAY INVISIBLE (-1466 1604);
FORCEPROP 2 LAST VOLTAGE 6.3V
J 2
(-1825 1575);
DISPLAY 0.553191 (-1825 1575);
DISPLAY INVISIBLE (-1825 1575);
FORCEPROP 1 LAST CDS_LMAN_SYM_OUTLINE -25,50,25,-50
J 2
(-1475 1525);
DISPLAY 0.468085 (-1475 1525);
PAINT GREEN (-1475 1525);
DISPLAY INVISIBLE (-1475 1525);
FORCEPROP 2 LAST CDS_LIB pure_quanta
J 2
(-1475 1525);
DISPLAY INVISIBLE (-1475 1525);
FORCEPROP 1 LAST PIN_NAMES_ROTATE TRUE
J 2
(-1475 1525);
DISPLAY 0.489362 (-1475 1525);
PAINT GREEN (-1475 1525);
DISPLAY INVISIBLE (-1475 1525);
FORCEPROP 1 LAST PATH I253
J 2
(-1475 1525);
DISPLAY 0.723404 (-1475 1525);
DISPLAY INVISIBLE (-1475 1525);
FORCEPROP 0 LAST CDS_LOCATION C1533
J 0
(-1225 1600);
DISPLAY 1.021277 (-1225 1600);
DISPLAY INVISIBLE (-1225 1600);
FORCEPROP 2 LAST $SEC 1
J 2
(-1300 1600);
DISPLAY 0.680851 (-1300 1600);
PAINT MONO (-1300 1600);
DISPLAY INVISIBLE (-1300 1600);
FORCEPROP 2 LAST CDS_SEC 1
J 2
(-1300 1600);
DISPLAY 0.680851 (-1300 1600);
DISPLAY INVISIBLE (-1300 1600);
FORCEADD Q_CAP_DIFFBUS..2
R 2
(-1475 1575);
FORCEPROP 1 LAST PART_NUMBER SP_CH4221MEE01
J 2
(-1591 1663);
DISPLAY 0.574468 (-1591 1663);
PAINT GREEN (-1591 1663);
DISPLAY INVISIBLE (-1591 1663);
FORCEPROP 2 LAST VALUE DIFF BUS_0.22UF
J 2
(-1625 1575);
DISPLAY 0.553191 (-1625 1575);
FORCEPROP 1 LAST $LOCATION C1532
J 2
(-1225 1600);
DISPLAY 0.723404 (-1225 1600);
PAINT GREEN (-1225 1600);
FORCEPROP 2 LASTPIN (-1400 1575) $PN 1
J 0
(-1390 1585);
DISPLAY 0.808511 (-1390 1585);
FORCEPROP 2 LASTPIN (-1550 1575) $PN 2
J 2
(-1560 1585);
DISPLAY 0.808511 (-1560 1585);
FORCEPROP 2 LAST TOLERANCE 20%
J 2
(-1550 1625);
DISPLAY 0.553191 (-1550 1625);
DISPLAY INVISIBLE (-1550 1625);
FORCEPROP 2 LAST PACK_TYPE C0201
J 2
(-1650 1625);
DISPLAY 0.553191 (-1650 1625);
DISPLAY INVISIBLE (-1650 1625);
FORCEPROP 1 LAST MATERIAL X6S
J 2
(-1466 1654);
DISPLAY 0.574468 (-1466 1654);
PAINT GREEN (-1466 1654);
DISPLAY INVISIBLE (-1466 1654);
FORCEPROP 2 LAST VOLTAGE 6.3V
J 2
(-1825 1625);
DISPLAY 0.553191 (-1825 1625);
DISPLAY INVISIBLE (-1825 1625);
FORCEPROP 2 LAST CDS_LIB pure_quanta
J 2
(-1475 1575);
DISPLAY INVISIBLE (-1475 1575);
FORCEPROP 1 LAST CDS_LMAN_SYM_OUTLINE -25,50,25,-50
J 2
(-1475 1575);
DISPLAY 0.468085 (-1475 1575);
PAINT GREEN (-1475 1575);
DISPLAY INVISIBLE (-1475 1575);
FORCEPROP 1 LAST PIN_NAMES_ROTATE TRUE
J 2
(-1475 1575);
DISPLAY 0.489362 (-1475 1575);
PAINT GREEN (-1475 1575);
DISPLAY INVISIBLE (-1475 1575);
FORCEPROP 1 LAST PATH I254
J 2
(-1475 1575);
DISPLAY 0.723404 (-1475 1575);
DISPLAY INVISIBLE (-1475 1575);
FORCEPROP 0 LAST CDS_LOCATION C1532
J 0
(-1225 1650);
DISPLAY 1.021277 (-1225 1650);
DISPLAY INVISIBLE (-1225 1650);
FORCEPROP 2 LAST $SEC 1
J 2
(-1300 1650);
DISPLAY 0.680851 (-1300 1650);
PAINT MONO (-1300 1650);
DISPLAY INVISIBLE (-1300 1650);
FORCEPROP 2 LAST CDS_SEC 1
J 2
(-1300 1650);
DISPLAY 0.680851 (-1300 1650);
DISPLAY INVISIBLE (-1300 1650);
FORCEADD TAP..1
(-925 1175);
FORCEPROP 3 LASTPIN (-975 1175) SIG_NAME P5E_CPU1_PE3_TX_C_DN<5>
J 0
(-965 1185);
DISPLAY 0.659574 (-965 1185);
PAINT MONO (-965 1185);
DISPLAY INVISIBLE (-965 1185);
FORCEPROP 1 LASTPIN (-975 1175) BN 5
J 0
(-987 1183);
DISPLAY 0.680851 (-987 1183);
PAINT GREEN (-987 1183);
FORCEPROP 2 LAST CDS_LIB standard
J 0
(-925 1175);
DISPLAY INVISIBLE (-925 1175);
FORCEPROP 1 LAST BODY_TYPE PLUMBING
J 0
(-925 1225);
DISPLAY 0.872340 (-925 1225);
PAINT GREEN (-925 1225);
DISPLAY INVISIBLE (-925 1225);
FORCEPROP 1 LAST HDL_TAP TRUE
J 0
(-600 1050);
DISPLAY 0.872340 (-600 1050);
DISPLAY INVISIBLE (-600 1050);
FORCEPROP 1 LAST PATH I255
J 0
(-927 1175);
DISPLAY 0.872340 (-927 1175);
PAINT GREEN (-927 1175);
DISPLAY INVISIBLE (-927 1175);
FORCEADD TAP..1
(-925 1375);
FORCEPROP 3 LASTPIN (-975 1375) SIG_NAME P5E_CPU1_PE3_TX_C_DN<6>
J 0
(-965 1385);
DISPLAY 0.659574 (-965 1385);
PAINT MONO (-965 1385);
DISPLAY INVISIBLE (-965 1385);
FORCEPROP 1 LASTPIN (-975 1375) BN 6
J 0
(-987 1383);
DISPLAY 0.680851 (-987 1383);
PAINT GREEN (-987 1383);
FORCEPROP 2 LAST CDS_LIB standard
J 0
(-925 1375);
DISPLAY INVISIBLE (-925 1375);
FORCEPROP 1 LAST BODY_TYPE PLUMBING
J 0
(-925 1425);
DISPLAY 0.872340 (-925 1425);
PAINT GREEN (-925 1425);
DISPLAY INVISIBLE (-925 1425);
FORCEPROP 1 LAST HDL_TAP TRUE
J 0
(-600 1250);
DISPLAY 0.872340 (-600 1250);
DISPLAY INVISIBLE (-600 1250);
FORCEPROP 1 LAST PATH I256
J 0
(-927 1375);
DISPLAY 0.872340 (-927 1375);
PAINT GREEN (-927 1375);
DISPLAY INVISIBLE (-927 1375);
FORCEADD TAP..1
(-725 1125);
FORCEPROP 3 LASTPIN (-775 1125) SIG_NAME P5E_CPU1_PE3_TX_C_DP<5>
J 0
(-765 1135);
DISPLAY 0.659574 (-765 1135);
PAINT MONO (-765 1135);
DISPLAY INVISIBLE (-765 1135);
FORCEPROP 1 LASTPIN (-775 1125) BN 5
J 0
(-787 1133);
DISPLAY 0.680851 (-787 1133);
PAINT GREEN (-787 1133);
FORCEPROP 2 LAST CDS_LIB standard
J 0
(-725 1125);
DISPLAY INVISIBLE (-725 1125);
FORCEPROP 1 LAST BODY_TYPE PLUMBING
J 0
(-725 1175);
DISPLAY 0.872340 (-725 1175);
PAINT GREEN (-725 1175);
DISPLAY INVISIBLE (-725 1175);
FORCEPROP 1 LAST HDL_TAP TRUE
J 0
(-400 1000);
DISPLAY 0.872340 (-400 1000);
DISPLAY INVISIBLE (-400 1000);
FORCEPROP 1 LAST PATH I257
J 0
(-727 1125);
DISPLAY 0.872340 (-727 1125);
PAINT GREEN (-727 1125);
DISPLAY INVISIBLE (-727 1125);
FORCEADD TAP..1
(-725 1325);
FORCEPROP 3 LASTPIN (-775 1325) SIG_NAME P5E_CPU1_PE3_TX_C_DP<6>
J 0
(-765 1335);
DISPLAY 0.659574 (-765 1335);
PAINT MONO (-765 1335);
DISPLAY INVISIBLE (-765 1335);
FORCEPROP 1 LASTPIN (-775 1325) BN 6
J 0
(-787 1333);
DISPLAY 0.680851 (-787 1333);
PAINT GREEN (-787 1333);
FORCEPROP 2 LAST CDS_LIB standard
J 0
(-725 1325);
DISPLAY INVISIBLE (-725 1325);
FORCEPROP 1 LAST BODY_TYPE PLUMBING
J 0
(-725 1375);
DISPLAY 0.872340 (-725 1375);
PAINT GREEN (-725 1375);
DISPLAY INVISIBLE (-725 1375);
FORCEPROP 1 LAST HDL_TAP TRUE
J 0
(-400 1200);
DISPLAY 0.872340 (-400 1200);
DISPLAY INVISIBLE (-400 1200);
FORCEPROP 1 LAST PATH I258
J 0
(-727 1325);
DISPLAY 0.872340 (-727 1325);
PAINT GREEN (-727 1325);
DISPLAY INVISIBLE (-727 1325);
FORCEADD TAP..1
(-925 1575);
FORCEPROP 3 LASTPIN (-975 1575) SIG_NAME P5E_CPU1_PE3_TX_C_DN<7>
J 0
(-965 1585);
DISPLAY 0.659574 (-965 1585);
PAINT MONO (-965 1585);
DISPLAY INVISIBLE (-965 1585);
FORCEPROP 1 LASTPIN (-975 1575) BN 7
J 0
(-987 1583);
DISPLAY 0.680851 (-987 1583);
PAINT GREEN (-987 1583);
FORCEPROP 2 LAST CDS_LIB standard
J 0
(-925 1575);
DISPLAY INVISIBLE (-925 1575);
FORCEPROP 1 LAST BODY_TYPE PLUMBING
J 0
(-925 1625);
DISPLAY 0.872340 (-925 1625);
PAINT GREEN (-925 1625);
DISPLAY INVISIBLE (-925 1625);
FORCEPROP 1 LAST HDL_TAP TRUE
J 0
(-600 1450);
DISPLAY 0.872340 (-600 1450);
DISPLAY INVISIBLE (-600 1450);
FORCEPROP 1 LAST PATH I259
J 0
(-927 1575);
DISPLAY 0.872340 (-927 1575);
PAINT GREEN (-927 1575);
DISPLAY INVISIBLE (-927 1575);
FORCEADD TAP..1
(-725 1525);
FORCEPROP 3 LASTPIN (-775 1525) SIG_NAME P5E_CPU1_PE3_TX_C_DP<7>
J 0
(-765 1535);
DISPLAY 0.659574 (-765 1535);
PAINT MONO (-765 1535);
DISPLAY INVISIBLE (-765 1535);
FORCEPROP 1 LASTPIN (-775 1525) BN 7
J 0
(-787 1533);
DISPLAY 0.680851 (-787 1533);
PAINT GREEN (-787 1533);
FORCEPROP 2 LAST CDS_LIB standard
J 0
(-725 1525);
DISPLAY INVISIBLE (-725 1525);
FORCEPROP 1 LAST BODY_TYPE PLUMBING
J 0
(-725 1575);
DISPLAY 0.872340 (-725 1575);
PAINT GREEN (-725 1575);
DISPLAY INVISIBLE (-725 1575);
FORCEPROP 1 LAST HDL_TAP TRUE
J 0
(-400 1400);
DISPLAY 0.872340 (-400 1400);
DISPLAY INVISIBLE (-400 1400);
FORCEPROP 1 LAST PATH I260
J 0
(-727 1525);
DISPLAY 0.872340 (-727 1525);
PAINT GREEN (-727 1525);
DISPLAY INVISIBLE (-727 1525);
FORCEADD TAP..1
R 2
(-2450 2100);
FORCEPROP 3 LASTPIN (-2400 2100) SIG_NAME P5E_CPU1_PE3_TX_DP<8>
J 0
(-2390 2110);
DISPLAY 0.659574 (-2390 2110);
PAINT MONO (-2390 2110);
DISPLAY INVISIBLE (-2390 2110);
FORCEPROP 1 LASTPIN (-2400 2100) BN 8
J 2
(-2388 2108);
DISPLAY 0.680851 (-2388 2108);
PAINT GREEN (-2388 2108);
FORCEPROP 2 LAST CDS_LIB standard
J 0
(-2450 2100);
DISPLAY INVISIBLE (-2450 2100);
FORCEPROP 1 LAST BODY_TYPE PLUMBING
J 2
(-2450 2150);
DISPLAY 0.872340 (-2450 2150);
PAINT GREEN (-2450 2150);
DISPLAY INVISIBLE (-2450 2150);
FORCEPROP 1 LAST HDL_TAP TRUE
J 2
(-2775 1975);
DISPLAY 0.872340 (-2775 1975);
DISPLAY INVISIBLE (-2775 1975);
FORCEPROP 1 LAST PATH I261
J 2
(-2448 2100);
DISPLAY 0.872340 (-2448 2100);
PAINT GREEN (-2448 2100);
DISPLAY INVISIBLE (-2448 2100);
FORCEADD TAP..1
R 2
(-2450 2500);
FORCEPROP 3 LASTPIN (-2400 2500) SIG_NAME P5E_CPU1_PE3_TX_DP<10>
J 0
(-2390 2510);
DISPLAY 0.659574 (-2390 2510);
PAINT MONO (-2390 2510);
DISPLAY INVISIBLE (-2390 2510);
FORCEPROP 1 LASTPIN (-2400 2500) BN 10
J 2
(-2388 2508);
DISPLAY 0.680851 (-2388 2508);
PAINT GREEN (-2388 2508);
FORCEPROP 2 LAST CDS_LIB standard
J 0
(-2450 2500);
DISPLAY INVISIBLE (-2450 2500);
FORCEPROP 1 LAST BODY_TYPE PLUMBING
J 2
(-2450 2550);
DISPLAY 0.872340 (-2450 2550);
PAINT GREEN (-2450 2550);
DISPLAY INVISIBLE (-2450 2550);
FORCEPROP 1 LAST HDL_TAP TRUE
J 2
(-2775 2375);
DISPLAY 0.872340 (-2775 2375);
DISPLAY INVISIBLE (-2775 2375);
FORCEPROP 1 LAST PATH I262
J 2
(-2448 2500);
DISPLAY 0.872340 (-2448 2500);
PAINT GREEN (-2448 2500);
DISPLAY INVISIBLE (-2448 2500);
FORCEADD TAP..1
R 2
(-2450 2300);
FORCEPROP 3 LASTPIN (-2400 2300) SIG_NAME P5E_CPU1_PE3_TX_DP<9>
J 0
(-2390 2310);
DISPLAY 0.659574 (-2390 2310);
PAINT MONO (-2390 2310);
DISPLAY INVISIBLE (-2390 2310);
FORCEPROP 1 LASTPIN (-2400 2300) BN 9
J 2
(-2388 2308);
DISPLAY 0.680851 (-2388 2308);
PAINT GREEN (-2388 2308);
FORCEPROP 2 LAST CDS_LIB standard
J 0
(-2450 2300);
DISPLAY INVISIBLE (-2450 2300);
FORCEPROP 1 LAST BODY_TYPE PLUMBING
J 2
(-2450 2350);
DISPLAY 0.872340 (-2450 2350);
PAINT GREEN (-2450 2350);
DISPLAY INVISIBLE (-2450 2350);
FORCEPROP 1 LAST HDL_TAP TRUE
J 2
(-2775 2175);
DISPLAY 0.872340 (-2775 2175);
DISPLAY INVISIBLE (-2775 2175);
FORCEPROP 1 LAST PATH I263
J 2
(-2448 2300);
DISPLAY 0.872340 (-2448 2300);
PAINT GREEN (-2448 2300);
DISPLAY INVISIBLE (-2448 2300);
FORCEADD TAP..1
R 2
(-2200 2150);
FORCEPROP 3 LASTPIN (-2150 2150) SIG_NAME P5E_CPU1_PE3_TX_DN<8>
J 0
(-2140 2160);
DISPLAY 0.659574 (-2140 2160);
PAINT MONO (-2140 2160);
DISPLAY INVISIBLE (-2140 2160);
FORCEPROP 1 LASTPIN (-2150 2150) BN 8
J 2
(-2138 2158);
DISPLAY 0.680851 (-2138 2158);
PAINT GREEN (-2138 2158);
FORCEPROP 2 LAST CDS_LIB standard
J 0
(-2200 2150);
DISPLAY INVISIBLE (-2200 2150);
FORCEPROP 1 LAST BODY_TYPE PLUMBING
J 2
(-2200 2200);
DISPLAY 0.872340 (-2200 2200);
PAINT GREEN (-2200 2200);
DISPLAY INVISIBLE (-2200 2200);
FORCEPROP 1 LAST HDL_TAP TRUE
J 2
(-2525 2025);
DISPLAY 0.872340 (-2525 2025);
DISPLAY INVISIBLE (-2525 2025);
FORCEPROP 1 LAST PATH I264
J 2
(-2198 2150);
DISPLAY 0.872340 (-2198 2150);
PAINT GREEN (-2198 2150);
DISPLAY INVISIBLE (-2198 2150);
FORCEADD TAP..1
R 2
(-2200 2350);
FORCEPROP 3 LASTPIN (-2150 2350) SIG_NAME P5E_CPU1_PE3_TX_DN<9>
J 0
(-2140 2360);
DISPLAY 0.659574 (-2140 2360);
PAINT MONO (-2140 2360);
DISPLAY INVISIBLE (-2140 2360);
FORCEPROP 1 LASTPIN (-2150 2350) BN 9
J 2
(-2138 2358);
DISPLAY 0.680851 (-2138 2358);
PAINT GREEN (-2138 2358);
FORCEPROP 2 LAST CDS_LIB standard
J 0
(-2200 2350);
DISPLAY INVISIBLE (-2200 2350);
FORCEPROP 1 LAST BODY_TYPE PLUMBING
J 2
(-2200 2400);
DISPLAY 0.872340 (-2200 2400);
PAINT GREEN (-2200 2400);
DISPLAY INVISIBLE (-2200 2400);
FORCEPROP 1 LAST HDL_TAP TRUE
J 2
(-2525 2225);
DISPLAY 0.872340 (-2525 2225);
DISPLAY INVISIBLE (-2525 2225);
FORCEPROP 1 LAST PATH I265
J 2
(-2198 2350);
DISPLAY 0.872340 (-2198 2350);
PAINT GREEN (-2198 2350);
DISPLAY INVISIBLE (-2198 2350);
FORCEADD TAP..1
R 2
(-2450 2700);
FORCEPROP 3 LASTPIN (-2400 2700) SIG_NAME P5E_CPU1_PE3_TX_DP<11>
J 0
(-2390 2710);
DISPLAY 0.659574 (-2390 2710);
PAINT MONO (-2390 2710);
DISPLAY INVISIBLE (-2390 2710);
FORCEPROP 1 LASTPIN (-2400 2700) BN 11
J 2
(-2388 2708);
DISPLAY 0.680851 (-2388 2708);
PAINT GREEN (-2388 2708);
FORCEPROP 2 LAST CDS_LIB standard
J 0
(-2450 2700);
DISPLAY INVISIBLE (-2450 2700);
FORCEPROP 1 LAST BODY_TYPE PLUMBING
J 2
(-2450 2750);
DISPLAY 0.872340 (-2450 2750);
PAINT GREEN (-2450 2750);
DISPLAY INVISIBLE (-2450 2750);
FORCEPROP 1 LAST HDL_TAP TRUE
J 2
(-2775 2575);
DISPLAY 0.872340 (-2775 2575);
DISPLAY INVISIBLE (-2775 2575);
FORCEPROP 1 LAST PATH I266
J 2
(-2448 2700);
DISPLAY 0.872340 (-2448 2700);
PAINT GREEN (-2448 2700);
DISPLAY INVISIBLE (-2448 2700);
FORCEADD TAP..1
R 2
(-2450 2900);
FORCEPROP 3 LASTPIN (-2400 2900) SIG_NAME P5E_CPU1_PE3_TX_DP<12>
J 0
(-2390 2910);
DISPLAY 0.659574 (-2390 2910);
PAINT MONO (-2390 2910);
DISPLAY INVISIBLE (-2390 2910);
FORCEPROP 1 LASTPIN (-2400 2900) BN 12
J 2
(-2388 2908);
DISPLAY 0.680851 (-2388 2908);
PAINT GREEN (-2388 2908);
FORCEPROP 2 LAST CDS_LIB standard
J 0
(-2450 2900);
DISPLAY INVISIBLE (-2450 2900);
FORCEPROP 1 LAST BODY_TYPE PLUMBING
J 2
(-2450 2950);
DISPLAY 0.872340 (-2450 2950);
PAINT GREEN (-2450 2950);
DISPLAY INVISIBLE (-2450 2950);
FORCEPROP 1 LAST HDL_TAP TRUE
J 2
(-2775 2775);
DISPLAY 0.872340 (-2775 2775);
DISPLAY INVISIBLE (-2775 2775);
FORCEPROP 1 LAST PATH I267
J 2
(-2448 2900);
DISPLAY 0.872340 (-2448 2900);
PAINT GREEN (-2448 2900);
DISPLAY INVISIBLE (-2448 2900);
FORCEADD TAP..1
R 2
(-2200 2750);
FORCEPROP 3 LASTPIN (-2150 2750) SIG_NAME P5E_CPU1_PE3_TX_DN<11>
J 0
(-2140 2760);
DISPLAY 0.659574 (-2140 2760);
PAINT MONO (-2140 2760);
DISPLAY INVISIBLE (-2140 2760);
FORCEPROP 1 LASTPIN (-2150 2750) BN 11
J 2
(-2138 2758);
DISPLAY 0.680851 (-2138 2758);
PAINT GREEN (-2138 2758);
FORCEPROP 2 LAST CDS_LIB standard
J 0
(-2200 2750);
DISPLAY INVISIBLE (-2200 2750);
FORCEPROP 1 LAST BODY_TYPE PLUMBING
J 2
(-2200 2800);
DISPLAY 0.872340 (-2200 2800);
PAINT GREEN (-2200 2800);
DISPLAY INVISIBLE (-2200 2800);
FORCEPROP 1 LAST HDL_TAP TRUE
J 2
(-2525 2625);
DISPLAY 0.872340 (-2525 2625);
DISPLAY INVISIBLE (-2525 2625);
FORCEPROP 1 LAST PATH I268
J 2
(-2198 2750);
DISPLAY 0.872340 (-2198 2750);
PAINT GREEN (-2198 2750);
DISPLAY INVISIBLE (-2198 2750);
FORCEADD TAP..1
R 2
(-2200 2550);
FORCEPROP 3 LASTPIN (-2150 2550) SIG_NAME P5E_CPU1_PE3_TX_DN<10>
J 0
(-2140 2560);
DISPLAY 0.659574 (-2140 2560);
PAINT MONO (-2140 2560);
DISPLAY INVISIBLE (-2140 2560);
FORCEPROP 1 LASTPIN (-2150 2550) BN 10
J 2
(-2138 2558);
DISPLAY 0.680851 (-2138 2558);
PAINT GREEN (-2138 2558);
FORCEPROP 2 LAST CDS_LIB standard
J 0
(-2200 2550);
DISPLAY INVISIBLE (-2200 2550);
FORCEPROP 1 LAST BODY_TYPE PLUMBING
J 2
(-2200 2600);
DISPLAY 0.872340 (-2200 2600);
PAINT GREEN (-2200 2600);
DISPLAY INVISIBLE (-2200 2600);
FORCEPROP 1 LAST HDL_TAP TRUE
J 2
(-2525 2425);
DISPLAY 0.872340 (-2525 2425);
DISPLAY INVISIBLE (-2525 2425);
FORCEPROP 1 LAST PATH I269
J 2
(-2198 2550);
DISPLAY 0.872340 (-2198 2550);
PAINT GREEN (-2198 2550);
DISPLAY INVISIBLE (-2198 2550);
FORCEADD TAP..1
R 2
(-2200 2950);
FORCEPROP 3 LASTPIN (-2150 2950) SIG_NAME P5E_CPU1_PE3_TX_DN<12>
J 0
(-2140 2960);
DISPLAY 0.659574 (-2140 2960);
PAINT MONO (-2140 2960);
DISPLAY INVISIBLE (-2140 2960);
FORCEPROP 1 LASTPIN (-2150 2950) BN 12
J 2
(-2138 2958);
DISPLAY 0.680851 (-2138 2958);
PAINT GREEN (-2138 2958);
FORCEPROP 2 LAST CDS_LIB standard
J 0
(-2200 2950);
DISPLAY INVISIBLE (-2200 2950);
FORCEPROP 1 LAST BODY_TYPE PLUMBING
J 2
(-2200 3000);
DISPLAY 0.872340 (-2200 3000);
PAINT GREEN (-2200 3000);
DISPLAY INVISIBLE (-2200 3000);
FORCEPROP 1 LAST HDL_TAP TRUE
J 2
(-2525 2825);
DISPLAY 0.872340 (-2525 2825);
DISPLAY INVISIBLE (-2525 2825);
FORCEPROP 1 LAST PATH I270
J 2
(-2198 2950);
DISPLAY 0.872340 (-2198 2950);
PAINT GREEN (-2198 2950);
DISPLAY INVISIBLE (-2198 2950);
FORCEADD TAP..1
R 2
(-2450 3100);
FORCEPROP 3 LASTPIN (-2400 3100) SIG_NAME P5E_CPU1_PE3_TX_DP<13>
J 0
(-2390 3110);
DISPLAY 0.659574 (-2390 3110);
PAINT MONO (-2390 3110);
DISPLAY INVISIBLE (-2390 3110);
FORCEPROP 1 LASTPIN (-2400 3100) BN 13
J 2
(-2388 3108);
DISPLAY 0.680851 (-2388 3108);
PAINT GREEN (-2388 3108);
FORCEPROP 2 LAST CDS_LIB standard
J 0
(-2450 3100);
DISPLAY INVISIBLE (-2450 3100);
FORCEPROP 1 LAST BODY_TYPE PLUMBING
J 2
(-2450 3150);
DISPLAY 0.872340 (-2450 3150);
PAINT GREEN (-2450 3150);
DISPLAY INVISIBLE (-2450 3150);
FORCEPROP 1 LAST HDL_TAP TRUE
J 2
(-2775 2975);
DISPLAY 0.872340 (-2775 2975);
DISPLAY INVISIBLE (-2775 2975);
FORCEPROP 1 LAST PATH I271
J 2
(-2448 3100);
DISPLAY 0.872340 (-2448 3100);
PAINT GREEN (-2448 3100);
DISPLAY INVISIBLE (-2448 3100);
FORCEADD TAP..1
R 2
(-2450 3300);
FORCEPROP 3 LASTPIN (-2400 3300) SIG_NAME P5E_CPU1_PE3_TX_DP<14>
J 0
(-2390 3310);
DISPLAY 0.659574 (-2390 3310);
PAINT MONO (-2390 3310);
DISPLAY INVISIBLE (-2390 3310);
FORCEPROP 1 LASTPIN (-2400 3300) BN 14
J 2
(-2388 3308);
DISPLAY 0.680851 (-2388 3308);
PAINT GREEN (-2388 3308);
FORCEPROP 2 LAST CDS_LIB standard
J 0
(-2450 3300);
DISPLAY INVISIBLE (-2450 3300);
FORCEPROP 1 LAST BODY_TYPE PLUMBING
J 2
(-2450 3350);
DISPLAY 0.872340 (-2450 3350);
PAINT GREEN (-2450 3350);
DISPLAY INVISIBLE (-2450 3350);
FORCEPROP 1 LAST HDL_TAP TRUE
J 2
(-2775 3175);
DISPLAY 0.872340 (-2775 3175);
DISPLAY INVISIBLE (-2775 3175);
FORCEPROP 1 LAST PATH I272
J 2
(-2448 3300);
DISPLAY 0.872340 (-2448 3300);
PAINT GREEN (-2448 3300);
DISPLAY INVISIBLE (-2448 3300);
FORCEADD TAP..1
R 2
(-2450 3500);
FORCEPROP 3 LASTPIN (-2400 3500) SIG_NAME P5E_CPU1_PE3_TX_DP<15>
J 0
(-2390 3510);
DISPLAY 0.659574 (-2390 3510);
PAINT MONO (-2390 3510);
DISPLAY INVISIBLE (-2390 3510);
FORCEPROP 1 LASTPIN (-2400 3500) BN 15
J 2
(-2388 3508);
DISPLAY 0.680851 (-2388 3508);
PAINT GREEN (-2388 3508);
FORCEPROP 2 LAST CDS_LIB standard
J 0
(-2450 3500);
DISPLAY INVISIBLE (-2450 3500);
FORCEPROP 1 LAST BODY_TYPE PLUMBING
J 2
(-2450 3550);
DISPLAY 0.872340 (-2450 3550);
PAINT GREEN (-2450 3550);
DISPLAY INVISIBLE (-2450 3550);
FORCEPROP 1 LAST HDL_TAP TRUE
J 2
(-2775 3375);
DISPLAY 0.872340 (-2775 3375);
DISPLAY INVISIBLE (-2775 3375);
FORCEPROP 1 LAST PATH I273
J 2
(-2448 3500);
DISPLAY 0.872340 (-2448 3500);
PAINT GREEN (-2448 3500);
DISPLAY INVISIBLE (-2448 3500);
FORCEADD TAP..1
R 2
(-2200 3150);
FORCEPROP 3 LASTPIN (-2150 3150) SIG_NAME P5E_CPU1_PE3_TX_DN<13>
J 0
(-2140 3160);
DISPLAY 0.659574 (-2140 3160);
PAINT MONO (-2140 3160);
DISPLAY INVISIBLE (-2140 3160);
FORCEPROP 1 LASTPIN (-2150 3150) BN 13
J 2
(-2138 3158);
DISPLAY 0.680851 (-2138 3158);
PAINT GREEN (-2138 3158);
FORCEPROP 2 LAST CDS_LIB standard
J 0
(-2200 3150);
DISPLAY INVISIBLE (-2200 3150);
FORCEPROP 1 LAST BODY_TYPE PLUMBING
J 2
(-2200 3200);
DISPLAY 0.872340 (-2200 3200);
PAINT GREEN (-2200 3200);
DISPLAY INVISIBLE (-2200 3200);
FORCEPROP 1 LAST HDL_TAP TRUE
J 2
(-2525 3025);
DISPLAY 0.872340 (-2525 3025);
DISPLAY INVISIBLE (-2525 3025);
FORCEPROP 1 LAST PATH I274
J 2
(-2198 3150);
DISPLAY 0.872340 (-2198 3150);
PAINT GREEN (-2198 3150);
DISPLAY INVISIBLE (-2198 3150);
FORCEADD TAP..1
R 2
(-2200 3350);
FORCEPROP 3 LASTPIN (-2150 3350) SIG_NAME P5E_CPU1_PE3_TX_DN<14>
J 0
(-2140 3360);
DISPLAY 0.659574 (-2140 3360);
PAINT MONO (-2140 3360);
DISPLAY INVISIBLE (-2140 3360);
FORCEPROP 1 LASTPIN (-2150 3350) BN 14
J 2
(-2138 3358);
DISPLAY 0.680851 (-2138 3358);
PAINT GREEN (-2138 3358);
FORCEPROP 2 LAST CDS_LIB standard
J 0
(-2200 3350);
DISPLAY INVISIBLE (-2200 3350);
FORCEPROP 1 LAST BODY_TYPE PLUMBING
J 2
(-2200 3400);
DISPLAY 0.872340 (-2200 3400);
PAINT GREEN (-2200 3400);
DISPLAY INVISIBLE (-2200 3400);
FORCEPROP 1 LAST HDL_TAP TRUE
J 2
(-2525 3225);
DISPLAY 0.872340 (-2525 3225);
DISPLAY INVISIBLE (-2525 3225);
FORCEPROP 1 LAST PATH I275
J 2
(-2198 3350);
DISPLAY 0.872340 (-2198 3350);
PAINT GREEN (-2198 3350);
DISPLAY INVISIBLE (-2198 3350);
FORCEADD TAP..1
R 2
(-2200 3550);
FORCEPROP 3 LASTPIN (-2150 3550) SIG_NAME P5E_CPU1_PE3_TX_DN<15>
J 0
(-2140 3560);
DISPLAY 0.659574 (-2140 3560);
PAINT MONO (-2140 3560);
DISPLAY INVISIBLE (-2140 3560);
FORCEPROP 1 LASTPIN (-2150 3550) BN 15
J 2
(-2138 3558);
DISPLAY 0.680851 (-2138 3558);
PAINT GREEN (-2138 3558);
FORCEPROP 2 LAST CDS_LIB standard
J 0
(-2200 3550);
DISPLAY INVISIBLE (-2200 3550);
FORCEPROP 1 LAST BODY_TYPE PLUMBING
J 2
(-2200 3600);
DISPLAY 0.872340 (-2200 3600);
PAINT GREEN (-2200 3600);
DISPLAY INVISIBLE (-2200 3600);
FORCEPROP 1 LAST HDL_TAP TRUE
J 2
(-2525 3425);
DISPLAY 0.872340 (-2525 3425);
DISPLAY INVISIBLE (-2525 3425);
FORCEPROP 1 LAST PATH I276
J 2
(-2198 3550);
DISPLAY 0.872340 (-2198 3550);
PAINT GREEN (-2198 3550);
DISPLAY INVISIBLE (-2198 3550);
FORCEADD Q_CAP_DIFFBUS..2
R 2
(-1475 2150);
FORCEPROP 1 LAST PART_NUMBER SP_CH4221MEE01
J 2
(-1591 2238);
DISPLAY 0.574468 (-1591 2238);
PAINT GREEN (-1591 2238);
DISPLAY INVISIBLE (-1591 2238);
FORCEPROP 2 LAST VALUE DIFF BUS_0.22UF
J 2
(-1625 2150);
DISPLAY 0.553191 (-1625 2150);
FORCEPROP 1 LAST $LOCATION C1530
J 2
(-1225 2175);
DISPLAY 0.723404 (-1225 2175);
PAINT GREEN (-1225 2175);
FORCEPROP 2 LASTPIN (-1400 2150) $PN 1
J 0
(-1390 2160);
DISPLAY 0.808511 (-1390 2160);
FORCEPROP 2 LASTPIN (-1550 2150) $PN 2
J 2
(-1560 2160);
DISPLAY 0.808511 (-1560 2160);
FORCEPROP 2 LAST TOLERANCE 20%
J 2
(-1550 2200);
DISPLAY 0.553191 (-1550 2200);
DISPLAY INVISIBLE (-1550 2200);
FORCEPROP 2 LAST PACK_TYPE C0201
J 2
(-1650 2200);
DISPLAY 0.553191 (-1650 2200);
DISPLAY INVISIBLE (-1650 2200);
FORCEPROP 1 LAST MATERIAL X6S
J 2
(-1466 2229);
DISPLAY 0.574468 (-1466 2229);
PAINT GREEN (-1466 2229);
DISPLAY INVISIBLE (-1466 2229);
FORCEPROP 2 LAST VOLTAGE 6.3V
J 2
(-1825 2200);
DISPLAY 0.553191 (-1825 2200);
DISPLAY INVISIBLE (-1825 2200);
FORCEPROP 1 LAST PIN_NAMES_ROTATE TRUE
J 2
(-1475 2150);
DISPLAY 0.489362 (-1475 2150);
PAINT GREEN (-1475 2150);
DISPLAY INVISIBLE (-1475 2150);
FORCEPROP 2 LAST CDS_LIB pure_quanta
J 2
(-1475 2150);
DISPLAY INVISIBLE (-1475 2150);
FORCEPROP 1 LAST CDS_LMAN_SYM_OUTLINE -25,50,25,-50
J 2
(-1475 2150);
DISPLAY 0.468085 (-1475 2150);
PAINT GREEN (-1475 2150);
DISPLAY INVISIBLE (-1475 2150);
FORCEPROP 1 LAST PATH I277
J 2
(-1475 2150);
DISPLAY 0.723404 (-1475 2150);
DISPLAY INVISIBLE (-1475 2150);
FORCEPROP 0 LAST CDS_LOCATION C1530
J 0
(-1225 2225);
DISPLAY 1.021277 (-1225 2225);
DISPLAY INVISIBLE (-1225 2225);
FORCEPROP 2 LAST $SEC 1
J 2
(-1300 2225);
DISPLAY 0.680851 (-1300 2225);
PAINT MONO (-1300 2225);
DISPLAY INVISIBLE (-1300 2225);
FORCEPROP 2 LAST CDS_SEC 1
J 2
(-1300 2225);
DISPLAY 0.680851 (-1300 2225);
DISPLAY INVISIBLE (-1300 2225);
FORCEADD Q_CAP_DIFFBUS..2
R 2
(-1475 2100);
FORCEPROP 1 LAST PART_NUMBER SP_CH4221MEE01
J 2
(-1591 2188);
DISPLAY 0.574468 (-1591 2188);
PAINT GREEN (-1591 2188);
DISPLAY INVISIBLE (-1591 2188);
FORCEPROP 2 LAST VALUE DIFF BUS_0.22UF
J 2
(-1625 2100);
DISPLAY 0.553191 (-1625 2100);
FORCEPROP 1 LAST $LOCATION C1531
J 2
(-1225 2125);
DISPLAY 0.723404 (-1225 2125);
PAINT GREEN (-1225 2125);
FORCEPROP 2 LASTPIN (-1400 2100) $PN 1
J 0
(-1390 2110);
DISPLAY 0.808511 (-1390 2110);
FORCEPROP 2 LASTPIN (-1550 2100) $PN 2
J 2
(-1560 2110);
DISPLAY 0.808511 (-1560 2110);
FORCEPROP 2 LAST TOLERANCE 20%
J 2
(-1550 2150);
DISPLAY 0.553191 (-1550 2150);
DISPLAY INVISIBLE (-1550 2150);
FORCEPROP 2 LAST PACK_TYPE C0201
J 2
(-1650 2150);
DISPLAY 0.553191 (-1650 2150);
DISPLAY INVISIBLE (-1650 2150);
FORCEPROP 1 LAST MATERIAL X6S
J 2
(-1466 2179);
DISPLAY 0.574468 (-1466 2179);
PAINT GREEN (-1466 2179);
DISPLAY INVISIBLE (-1466 2179);
FORCEPROP 2 LAST VOLTAGE 6.3V
J 2
(-1825 2150);
DISPLAY 0.553191 (-1825 2150);
DISPLAY INVISIBLE (-1825 2150);
FORCEPROP 1 LAST PIN_NAMES_ROTATE TRUE
J 2
(-1475 2100);
DISPLAY 0.489362 (-1475 2100);
PAINT GREEN (-1475 2100);
DISPLAY INVISIBLE (-1475 2100);
FORCEPROP 2 LAST CDS_LIB pure_quanta
J 2
(-1475 2100);
DISPLAY INVISIBLE (-1475 2100);
FORCEPROP 1 LAST CDS_LMAN_SYM_OUTLINE -25,50,25,-50
J 2
(-1475 2100);
DISPLAY 0.468085 (-1475 2100);
PAINT GREEN (-1475 2100);
DISPLAY INVISIBLE (-1475 2100);
FORCEPROP 1 LAST PATH I278
J 2
(-1475 2100);
DISPLAY 0.723404 (-1475 2100);
DISPLAY INVISIBLE (-1475 2100);
FORCEPROP 0 LAST CDS_LOCATION C1531
J 0
(-1225 2175);
DISPLAY 1.021277 (-1225 2175);
DISPLAY INVISIBLE (-1225 2175);
FORCEPROP 2 LAST $SEC 1
J 2
(-1300 2175);
DISPLAY 0.680851 (-1300 2175);
PAINT MONO (-1300 2175);
DISPLAY INVISIBLE (-1300 2175);
FORCEPROP 2 LAST CDS_SEC 1
J 2
(-1300 2175);
DISPLAY 0.680851 (-1300 2175);
DISPLAY INVISIBLE (-1300 2175);
FORCEADD Q_CAP_DIFFBUS..2
R 2
(-1475 2300);
FORCEPROP 1 LAST PART_NUMBER SP_CH4221MEE01
J 2
(-1591 2388);
DISPLAY 0.574468 (-1591 2388);
PAINT GREEN (-1591 2388);
DISPLAY INVISIBLE (-1591 2388);
FORCEPROP 2 LAST VALUE DIFF BUS_0.22UF
J 2
(-1625 2300);
DISPLAY 0.553191 (-1625 2300);
FORCEPROP 1 LAST $LOCATION C1529
J 2
(-1225 2325);
DISPLAY 0.723404 (-1225 2325);
PAINT GREEN (-1225 2325);
FORCEPROP 2 LASTPIN (-1400 2300) $PN 1
J 0
(-1390 2310);
DISPLAY 0.808511 (-1390 2310);
FORCEPROP 2 LASTPIN (-1550 2300) $PN 2
J 2
(-1560 2310);
DISPLAY 0.808511 (-1560 2310);
FORCEPROP 2 LAST TOLERANCE 20%
J 2
(-1550 2350);
DISPLAY 0.553191 (-1550 2350);
DISPLAY INVISIBLE (-1550 2350);
FORCEPROP 2 LAST PACK_TYPE C0201
J 2
(-1650 2350);
DISPLAY 0.553191 (-1650 2350);
DISPLAY INVISIBLE (-1650 2350);
FORCEPROP 1 LAST MATERIAL X6S
J 2
(-1466 2379);
DISPLAY 0.574468 (-1466 2379);
PAINT GREEN (-1466 2379);
DISPLAY INVISIBLE (-1466 2379);
FORCEPROP 2 LAST VOLTAGE 6.3V
J 2
(-1825 2350);
DISPLAY 0.553191 (-1825 2350);
DISPLAY INVISIBLE (-1825 2350);
FORCEPROP 1 LAST PIN_NAMES_ROTATE TRUE
J 2
(-1475 2300);
DISPLAY 0.489362 (-1475 2300);
PAINT GREEN (-1475 2300);
DISPLAY INVISIBLE (-1475 2300);
FORCEPROP 2 LAST CDS_LIB pure_quanta
J 2
(-1475 2300);
DISPLAY INVISIBLE (-1475 2300);
FORCEPROP 1 LAST CDS_LMAN_SYM_OUTLINE -25,50,25,-50
J 2
(-1475 2300);
DISPLAY 0.468085 (-1475 2300);
PAINT GREEN (-1475 2300);
DISPLAY INVISIBLE (-1475 2300);
FORCEPROP 1 LAST PATH I279
J 2
(-1475 2300);
DISPLAY 0.723404 (-1475 2300);
DISPLAY INVISIBLE (-1475 2300);
FORCEPROP 0 LAST CDS_LOCATION C1529
J 0
(-1225 2375);
DISPLAY 1.021277 (-1225 2375);
DISPLAY INVISIBLE (-1225 2375);
FORCEPROP 2 LAST $SEC 1
J 2
(-1300 2375);
DISPLAY 0.680851 (-1300 2375);
PAINT MONO (-1300 2375);
DISPLAY INVISIBLE (-1300 2375);
FORCEPROP 2 LAST CDS_SEC 1
J 2
(-1300 2375);
DISPLAY 0.680851 (-1300 2375);
DISPLAY INVISIBLE (-1300 2375);
FORCEADD Q_CAP_DIFFBUS..2
R 2
(-1475 2350);
FORCEPROP 1 LAST PART_NUMBER SP_CH4221MEE01
J 2
(-1591 2438);
DISPLAY 0.574468 (-1591 2438);
PAINT GREEN (-1591 2438);
DISPLAY INVISIBLE (-1591 2438);
FORCEPROP 2 LAST VALUE DIFF BUS_0.22UF
J 2
(-1625 2350);
DISPLAY 0.553191 (-1625 2350);
FORCEPROP 1 LAST $LOCATION C1528
J 2
(-1225 2375);
DISPLAY 0.723404 (-1225 2375);
PAINT GREEN (-1225 2375);
FORCEPROP 2 LASTPIN (-1400 2350) $PN 1
J 0
(-1390 2360);
DISPLAY 0.808511 (-1390 2360);
FORCEPROP 2 LASTPIN (-1550 2350) $PN 2
J 2
(-1560 2360);
DISPLAY 0.808511 (-1560 2360);
FORCEPROP 2 LAST TOLERANCE 20%
J 2
(-1550 2400);
DISPLAY 0.553191 (-1550 2400);
DISPLAY INVISIBLE (-1550 2400);
FORCEPROP 2 LAST PACK_TYPE C0201
J 2
(-1650 2400);
DISPLAY 0.553191 (-1650 2400);
DISPLAY INVISIBLE (-1650 2400);
FORCEPROP 1 LAST MATERIAL X6S
J 2
(-1466 2429);
DISPLAY 0.574468 (-1466 2429);
PAINT GREEN (-1466 2429);
DISPLAY INVISIBLE (-1466 2429);
FORCEPROP 2 LAST VOLTAGE 6.3V
J 2
(-1825 2400);
DISPLAY 0.553191 (-1825 2400);
DISPLAY INVISIBLE (-1825 2400);
FORCEPROP 1 LAST PIN_NAMES_ROTATE TRUE
J 2
(-1475 2350);
DISPLAY 0.489362 (-1475 2350);
PAINT GREEN (-1475 2350);
DISPLAY INVISIBLE (-1475 2350);
FORCEPROP 1 LAST CDS_LMAN_SYM_OUTLINE -25,50,25,-50
J 2
(-1475 2350);
DISPLAY 0.468085 (-1475 2350);
PAINT GREEN (-1475 2350);
DISPLAY INVISIBLE (-1475 2350);
FORCEPROP 2 LAST CDS_LIB pure_quanta
J 2
(-1475 2350);
DISPLAY INVISIBLE (-1475 2350);
FORCEPROP 1 LAST PATH I280
J 2
(-1475 2350);
DISPLAY 0.723404 (-1475 2350);
DISPLAY INVISIBLE (-1475 2350);
FORCEPROP 0 LAST CDS_LOCATION C1528
J 0
(-1225 2425);
DISPLAY 1.021277 (-1225 2425);
DISPLAY INVISIBLE (-1225 2425);
FORCEPROP 2 LAST $SEC 1
J 2
(-1300 2425);
DISPLAY 0.680851 (-1300 2425);
PAINT MONO (-1300 2425);
DISPLAY INVISIBLE (-1300 2425);
FORCEPROP 2 LAST CDS_SEC 1
J 2
(-1300 2425);
DISPLAY 0.680851 (-1300 2425);
DISPLAY INVISIBLE (-1300 2425);
FORCEADD Q_CAP_DIFFBUS..2
R 2
(-1475 2500);
FORCEPROP 1 LAST PART_NUMBER SP_CH4221MEE01
J 2
(-1591 2588);
DISPLAY 0.574468 (-1591 2588);
PAINT GREEN (-1591 2588);
DISPLAY INVISIBLE (-1591 2588);
FORCEPROP 2 LAST VALUE DIFF BUS_0.22UF
J 2
(-1625 2500);
DISPLAY 0.553191 (-1625 2500);
FORCEPROP 1 LAST $LOCATION C1527
J 2
(-1225 2525);
DISPLAY 0.723404 (-1225 2525);
PAINT GREEN (-1225 2525);
FORCEPROP 2 LASTPIN (-1400 2500) $PN 1
J 0
(-1390 2510);
DISPLAY 0.808511 (-1390 2510);
FORCEPROP 2 LASTPIN (-1550 2500) $PN 2
J 2
(-1560 2510);
DISPLAY 0.808511 (-1560 2510);
FORCEPROP 2 LAST TOLERANCE 20%
J 2
(-1550 2550);
DISPLAY 0.553191 (-1550 2550);
DISPLAY INVISIBLE (-1550 2550);
FORCEPROP 2 LAST PACK_TYPE C0201
J 2
(-1650 2550);
DISPLAY 0.553191 (-1650 2550);
DISPLAY INVISIBLE (-1650 2550);
FORCEPROP 1 LAST MATERIAL X6S
J 2
(-1466 2579);
DISPLAY 0.574468 (-1466 2579);
PAINT GREEN (-1466 2579);
DISPLAY INVISIBLE (-1466 2579);
FORCEPROP 2 LAST VOLTAGE 6.3V
J 2
(-1825 2550);
DISPLAY 0.553191 (-1825 2550);
DISPLAY INVISIBLE (-1825 2550);
FORCEPROP 1 LAST PIN_NAMES_ROTATE TRUE
J 2
(-1475 2500);
DISPLAY 0.489362 (-1475 2500);
PAINT GREEN (-1475 2500);
DISPLAY INVISIBLE (-1475 2500);
FORCEPROP 2 LAST CDS_LIB pure_quanta
J 2
(-1475 2500);
DISPLAY INVISIBLE (-1475 2500);
FORCEPROP 1 LAST CDS_LMAN_SYM_OUTLINE -25,50,25,-50
J 2
(-1475 2500);
DISPLAY 0.468085 (-1475 2500);
PAINT GREEN (-1475 2500);
DISPLAY INVISIBLE (-1475 2500);
FORCEPROP 1 LAST PATH I281
J 2
(-1475 2500);
DISPLAY 0.723404 (-1475 2500);
DISPLAY INVISIBLE (-1475 2500);
FORCEPROP 0 LAST CDS_LOCATION C1527
J 0
(-1225 2575);
DISPLAY 1.021277 (-1225 2575);
DISPLAY INVISIBLE (-1225 2575);
FORCEPROP 2 LAST $SEC 1
J 2
(-1300 2575);
DISPLAY 0.680851 (-1300 2575);
PAINT MONO (-1300 2575);
DISPLAY INVISIBLE (-1300 2575);
FORCEPROP 2 LAST CDS_SEC 1
J 2
(-1300 2575);
DISPLAY 0.680851 (-1300 2575);
DISPLAY INVISIBLE (-1300 2575);
FORCEADD Q_CAP_DIFFBUS..2
R 2
(-1475 2550);
FORCEPROP 1 LAST PART_NUMBER SP_CH4221MEE01
J 2
(-1591 2638);
DISPLAY 0.574468 (-1591 2638);
PAINT GREEN (-1591 2638);
DISPLAY INVISIBLE (-1591 2638);
FORCEPROP 2 LAST VALUE DIFF BUS_0.22UF
J 2
(-1625 2550);
DISPLAY 0.553191 (-1625 2550);
FORCEPROP 1 LAST $LOCATION C1526
J 2
(-1225 2575);
DISPLAY 0.723404 (-1225 2575);
PAINT GREEN (-1225 2575);
FORCEPROP 2 LASTPIN (-1400 2550) $PN 1
J 0
(-1390 2560);
DISPLAY 0.808511 (-1390 2560);
FORCEPROP 2 LASTPIN (-1550 2550) $PN 2
J 2
(-1560 2560);
DISPLAY 0.808511 (-1560 2560);
FORCEPROP 2 LAST TOLERANCE 20%
J 2
(-1550 2600);
DISPLAY 0.553191 (-1550 2600);
DISPLAY INVISIBLE (-1550 2600);
FORCEPROP 2 LAST PACK_TYPE C0201
J 2
(-1650 2600);
DISPLAY 0.553191 (-1650 2600);
DISPLAY INVISIBLE (-1650 2600);
FORCEPROP 1 LAST MATERIAL X6S
J 2
(-1466 2629);
DISPLAY 0.574468 (-1466 2629);
PAINT GREEN (-1466 2629);
DISPLAY INVISIBLE (-1466 2629);
FORCEPROP 2 LAST VOLTAGE 6.3V
J 2
(-1825 2600);
DISPLAY 0.553191 (-1825 2600);
DISPLAY INVISIBLE (-1825 2600);
FORCEPROP 1 LAST PIN_NAMES_ROTATE TRUE
J 2
(-1475 2550);
DISPLAY 0.489362 (-1475 2550);
PAINT GREEN (-1475 2550);
DISPLAY INVISIBLE (-1475 2550);
FORCEPROP 2 LAST CDS_LIB pure_quanta
J 2
(-1475 2550);
DISPLAY INVISIBLE (-1475 2550);
FORCEPROP 1 LAST CDS_LMAN_SYM_OUTLINE -25,50,25,-50
J 2
(-1475 2550);
DISPLAY 0.468085 (-1475 2550);
PAINT GREEN (-1475 2550);
DISPLAY INVISIBLE (-1475 2550);
FORCEPROP 1 LAST PATH I282
J 2
(-1475 2550);
DISPLAY 0.723404 (-1475 2550);
DISPLAY INVISIBLE (-1475 2550);
FORCEPROP 0 LAST CDS_LOCATION C1526
J 0
(-1225 2625);
DISPLAY 1.021277 (-1225 2625);
DISPLAY INVISIBLE (-1225 2625);
FORCEPROP 2 LAST $SEC 1
J 2
(-1300 2625);
DISPLAY 0.680851 (-1300 2625);
PAINT MONO (-1300 2625);
DISPLAY INVISIBLE (-1300 2625);
FORCEPROP 2 LAST CDS_SEC 1
J 2
(-1300 2625);
DISPLAY 0.680851 (-1300 2625);
DISPLAY INVISIBLE (-1300 2625);
FORCEADD Q_CAP_DIFFBUS..2
R 2
(-1475 2700);
FORCEPROP 1 LAST PART_NUMBER SP_CH4221MEE01
J 2
(-1591 2788);
DISPLAY 0.574468 (-1591 2788);
PAINT GREEN (-1591 2788);
DISPLAY INVISIBLE (-1591 2788);
FORCEPROP 2 LAST VALUE DIFF BUS_0.22UF
J 2
(-1625 2700);
DISPLAY 0.553191 (-1625 2700);
FORCEPROP 1 LAST $LOCATION C1525
J 2
(-1225 2725);
DISPLAY 0.723404 (-1225 2725);
PAINT GREEN (-1225 2725);
FORCEPROP 2 LASTPIN (-1400 2700) $PN 1
J 0
(-1390 2710);
DISPLAY 0.808511 (-1390 2710);
FORCEPROP 2 LASTPIN (-1550 2700) $PN 2
J 2
(-1560 2710);
DISPLAY 0.808511 (-1560 2710);
FORCEPROP 2 LAST TOLERANCE 20%
J 2
(-1550 2750);
DISPLAY 0.553191 (-1550 2750);
DISPLAY INVISIBLE (-1550 2750);
FORCEPROP 2 LAST PACK_TYPE C0201
J 2
(-1650 2750);
DISPLAY 0.553191 (-1650 2750);
DISPLAY INVISIBLE (-1650 2750);
FORCEPROP 1 LAST MATERIAL X6S
J 2
(-1466 2779);
DISPLAY 0.574468 (-1466 2779);
PAINT GREEN (-1466 2779);
DISPLAY INVISIBLE (-1466 2779);
FORCEPROP 2 LAST VOLTAGE 6.3V
J 2
(-1825 2750);
DISPLAY 0.553191 (-1825 2750);
DISPLAY INVISIBLE (-1825 2750);
FORCEPROP 1 LAST PIN_NAMES_ROTATE TRUE
J 2
(-1475 2700);
DISPLAY 0.489362 (-1475 2700);
PAINT GREEN (-1475 2700);
DISPLAY INVISIBLE (-1475 2700);
FORCEPROP 1 LAST CDS_LMAN_SYM_OUTLINE -25,50,25,-50
J 2
(-1475 2700);
DISPLAY 0.468085 (-1475 2700);
PAINT GREEN (-1475 2700);
DISPLAY INVISIBLE (-1475 2700);
FORCEPROP 2 LAST CDS_LIB pure_quanta
J 2
(-1475 2700);
DISPLAY INVISIBLE (-1475 2700);
FORCEPROP 1 LAST PATH I283
J 2
(-1475 2700);
DISPLAY 0.723404 (-1475 2700);
DISPLAY INVISIBLE (-1475 2700);
FORCEPROP 0 LAST CDS_LOCATION C1525
J 0
(-1225 2775);
DISPLAY 1.021277 (-1225 2775);
DISPLAY INVISIBLE (-1225 2775);
FORCEPROP 2 LAST $SEC 1
J 2
(-1300 2775);
DISPLAY 0.680851 (-1300 2775);
PAINT MONO (-1300 2775);
DISPLAY INVISIBLE (-1300 2775);
FORCEPROP 2 LAST CDS_SEC 1
J 2
(-1300 2775);
DISPLAY 0.680851 (-1300 2775);
DISPLAY INVISIBLE (-1300 2775);
FORCEADD Q_CAP_DIFFBUS..2
R 2
(-1475 2750);
FORCEPROP 1 LAST PART_NUMBER SP_CH4221MEE01
J 2
(-1591 2838);
DISPLAY 0.574468 (-1591 2838);
PAINT GREEN (-1591 2838);
DISPLAY INVISIBLE (-1591 2838);
FORCEPROP 2 LAST VALUE DIFF BUS_0.22UF
J 2
(-1625 2750);
DISPLAY 0.553191 (-1625 2750);
FORCEPROP 1 LAST $LOCATION C1524
J 2
(-1225 2775);
DISPLAY 0.723404 (-1225 2775);
PAINT GREEN (-1225 2775);
FORCEPROP 2 LASTPIN (-1400 2750) $PN 1
J 0
(-1390 2760);
DISPLAY 0.808511 (-1390 2760);
FORCEPROP 2 LASTPIN (-1550 2750) $PN 2
J 2
(-1560 2760);
DISPLAY 0.808511 (-1560 2760);
FORCEPROP 2 LAST TOLERANCE 20%
J 2
(-1550 2800);
DISPLAY 0.553191 (-1550 2800);
DISPLAY INVISIBLE (-1550 2800);
FORCEPROP 2 LAST PACK_TYPE C0201
J 2
(-1650 2800);
DISPLAY 0.553191 (-1650 2800);
DISPLAY INVISIBLE (-1650 2800);
FORCEPROP 1 LAST MATERIAL X6S
J 2
(-1466 2829);
DISPLAY 0.574468 (-1466 2829);
PAINT GREEN (-1466 2829);
DISPLAY INVISIBLE (-1466 2829);
FORCEPROP 2 LAST VOLTAGE 6.3V
J 2
(-1825 2800);
DISPLAY 0.553191 (-1825 2800);
DISPLAY INVISIBLE (-1825 2800);
FORCEPROP 1 LAST PIN_NAMES_ROTATE TRUE
J 2
(-1475 2750);
DISPLAY 0.489362 (-1475 2750);
PAINT GREEN (-1475 2750);
DISPLAY INVISIBLE (-1475 2750);
FORCEPROP 1 LAST CDS_LMAN_SYM_OUTLINE -25,50,25,-50
J 2
(-1475 2750);
DISPLAY 0.468085 (-1475 2750);
PAINT GREEN (-1475 2750);
DISPLAY INVISIBLE (-1475 2750);
FORCEPROP 2 LAST CDS_LIB pure_quanta
J 2
(-1475 2750);
DISPLAY INVISIBLE (-1475 2750);
FORCEPROP 1 LAST PATH I284
J 2
(-1475 2750);
DISPLAY 0.723404 (-1475 2750);
DISPLAY INVISIBLE (-1475 2750);
FORCEPROP 0 LAST CDS_LOCATION C1524
J 0
(-1225 2825);
DISPLAY 1.021277 (-1225 2825);
DISPLAY INVISIBLE (-1225 2825);
FORCEPROP 2 LAST $SEC 1
J 2
(-1300 2825);
DISPLAY 0.680851 (-1300 2825);
PAINT MONO (-1300 2825);
DISPLAY INVISIBLE (-1300 2825);
FORCEPROP 2 LAST CDS_SEC 1
J 2
(-1300 2825);
DISPLAY 0.680851 (-1300 2825);
DISPLAY INVISIBLE (-1300 2825);
FORCEADD Q_CAP_DIFFBUS..2
R 2
(-1475 2900);
FORCEPROP 1 LAST PART_NUMBER SP_CH4221MEE01
J 2
(-1591 2988);
DISPLAY 0.574468 (-1591 2988);
PAINT GREEN (-1591 2988);
DISPLAY INVISIBLE (-1591 2988);
FORCEPROP 2 LAST VALUE DIFF BUS_0.22UF
J 2
(-1625 2900);
DISPLAY 0.553191 (-1625 2900);
FORCEPROP 1 LAST $LOCATION C1523
J 2
(-1225 2925);
DISPLAY 0.723404 (-1225 2925);
PAINT GREEN (-1225 2925);
FORCEPROP 2 LASTPIN (-1400 2900) $PN 1
J 0
(-1390 2910);
DISPLAY 0.808511 (-1390 2910);
FORCEPROP 2 LASTPIN (-1550 2900) $PN 2
J 2
(-1560 2910);
DISPLAY 0.808511 (-1560 2910);
FORCEPROP 2 LAST TOLERANCE 20%
J 2
(-1550 2950);
DISPLAY 0.553191 (-1550 2950);
DISPLAY INVISIBLE (-1550 2950);
FORCEPROP 2 LAST PACK_TYPE C0201
J 2
(-1650 2950);
DISPLAY 0.553191 (-1650 2950);
DISPLAY INVISIBLE (-1650 2950);
FORCEPROP 1 LAST MATERIAL X6S
J 2
(-1466 2979);
DISPLAY 0.574468 (-1466 2979);
PAINT GREEN (-1466 2979);
DISPLAY INVISIBLE (-1466 2979);
FORCEPROP 2 LAST VOLTAGE 6.3V
J 2
(-1825 2950);
DISPLAY 0.553191 (-1825 2950);
DISPLAY INVISIBLE (-1825 2950);
FORCEPROP 1 LAST PIN_NAMES_ROTATE TRUE
J 2
(-1475 2900);
DISPLAY 0.489362 (-1475 2900);
PAINT GREEN (-1475 2900);
DISPLAY INVISIBLE (-1475 2900);
FORCEPROP 2 LAST CDS_LIB pure_quanta
J 2
(-1475 2900);
DISPLAY INVISIBLE (-1475 2900);
FORCEPROP 1 LAST CDS_LMAN_SYM_OUTLINE -25,50,25,-50
J 2
(-1475 2900);
DISPLAY 0.468085 (-1475 2900);
PAINT GREEN (-1475 2900);
DISPLAY INVISIBLE (-1475 2900);
FORCEPROP 1 LAST PATH I285
J 2
(-1475 2900);
DISPLAY 0.723404 (-1475 2900);
DISPLAY INVISIBLE (-1475 2900);
FORCEPROP 0 LAST CDS_LOCATION C1523
J 0
(-1225 2975);
DISPLAY 1.021277 (-1225 2975);
DISPLAY INVISIBLE (-1225 2975);
FORCEPROP 2 LAST $SEC 1
J 2
(-1300 2975);
DISPLAY 0.680851 (-1300 2975);
PAINT MONO (-1300 2975);
DISPLAY INVISIBLE (-1300 2975);
FORCEPROP 2 LAST CDS_SEC 1
J 2
(-1300 2975);
DISPLAY 0.680851 (-1300 2975);
DISPLAY INVISIBLE (-1300 2975);
FORCEADD Q_CAP_DIFFBUS..2
R 2
(-1475 2950);
FORCEPROP 1 LAST PART_NUMBER SP_CH4221MEE01
J 2
(-1591 3038);
DISPLAY 0.574468 (-1591 3038);
PAINT GREEN (-1591 3038);
DISPLAY INVISIBLE (-1591 3038);
FORCEPROP 2 LAST VALUE DIFF BUS_0.22UF
J 2
(-1625 2950);
DISPLAY 0.553191 (-1625 2950);
FORCEPROP 1 LAST $LOCATION C1522
J 2
(-1225 2975);
DISPLAY 0.723404 (-1225 2975);
PAINT GREEN (-1225 2975);
FORCEPROP 2 LASTPIN (-1400 2950) $PN 1
J 0
(-1390 2960);
DISPLAY 0.808511 (-1390 2960);
FORCEPROP 2 LASTPIN (-1550 2950) $PN 2
J 2
(-1560 2960);
DISPLAY 0.808511 (-1560 2960);
FORCEPROP 2 LAST TOLERANCE 20%
J 2
(-1550 3000);
DISPLAY 0.553191 (-1550 3000);
DISPLAY INVISIBLE (-1550 3000);
FORCEPROP 2 LAST PACK_TYPE C0201
J 2
(-1650 3000);
DISPLAY 0.553191 (-1650 3000);
DISPLAY INVISIBLE (-1650 3000);
FORCEPROP 1 LAST MATERIAL X6S
J 2
(-1466 3029);
DISPLAY 0.574468 (-1466 3029);
PAINT GREEN (-1466 3029);
DISPLAY INVISIBLE (-1466 3029);
FORCEPROP 2 LAST VOLTAGE 6.3V
J 2
(-1825 3000);
DISPLAY 0.553191 (-1825 3000);
DISPLAY INVISIBLE (-1825 3000);
FORCEPROP 1 LAST PIN_NAMES_ROTATE TRUE
J 2
(-1475 2950);
DISPLAY 0.489362 (-1475 2950);
PAINT GREEN (-1475 2950);
DISPLAY INVISIBLE (-1475 2950);
FORCEPROP 2 LAST CDS_LIB pure_quanta
J 2
(-1475 2950);
DISPLAY INVISIBLE (-1475 2950);
FORCEPROP 1 LAST CDS_LMAN_SYM_OUTLINE -25,50,25,-50
J 2
(-1475 2950);
DISPLAY 0.468085 (-1475 2950);
PAINT GREEN (-1475 2950);
DISPLAY INVISIBLE (-1475 2950);
FORCEPROP 1 LAST PATH I286
J 2
(-1475 2950);
DISPLAY 0.723404 (-1475 2950);
DISPLAY INVISIBLE (-1475 2950);
FORCEPROP 0 LAST CDS_LOCATION C1522
J 0
(-1225 3025);
DISPLAY 1.021277 (-1225 3025);
DISPLAY INVISIBLE (-1225 3025);
FORCEPROP 2 LAST $SEC 1
J 2
(-1300 3025);
DISPLAY 0.680851 (-1300 3025);
PAINT MONO (-1300 3025);
DISPLAY INVISIBLE (-1300 3025);
FORCEPROP 2 LAST CDS_SEC 1
J 2
(-1300 3025);
DISPLAY 0.680851 (-1300 3025);
DISPLAY INVISIBLE (-1300 3025);
FORCEADD TAP..1
(-925 2150);
FORCEPROP 3 LASTPIN (-975 2150) SIG_NAME P5E_CPU1_PE3_TX_C_DN<8>
J 0
(-965 2160);
DISPLAY 0.659574 (-965 2160);
PAINT MONO (-965 2160);
DISPLAY INVISIBLE (-965 2160);
FORCEPROP 1 LASTPIN (-975 2150) BN 8
J 0
(-987 2158);
DISPLAY 0.680851 (-987 2158);
PAINT GREEN (-987 2158);
FORCEPROP 2 LAST CDS_LIB standard
J 0
(-925 2150);
DISPLAY INVISIBLE (-925 2150);
FORCEPROP 1 LAST BODY_TYPE PLUMBING
J 0
(-925 2200);
DISPLAY 0.872340 (-925 2200);
PAINT GREEN (-925 2200);
DISPLAY INVISIBLE (-925 2200);
FORCEPROP 1 LAST HDL_TAP TRUE
J 0
(-600 2025);
DISPLAY 0.872340 (-600 2025);
DISPLAY INVISIBLE (-600 2025);
FORCEPROP 1 LAST PATH I287
J 0
(-927 2150);
DISPLAY 0.872340 (-927 2150);
PAINT GREEN (-927 2150);
DISPLAY INVISIBLE (-927 2150);
FORCEADD TAP..1
(-925 2350);
FORCEPROP 3 LASTPIN (-975 2350) SIG_NAME P5E_CPU1_PE3_TX_C_DN<9>
J 0
(-965 2360);
DISPLAY 0.659574 (-965 2360);
PAINT MONO (-965 2360);
DISPLAY INVISIBLE (-965 2360);
FORCEPROP 1 LASTPIN (-975 2350) BN 9
J 0
(-987 2358);
DISPLAY 0.680851 (-987 2358);
PAINT GREEN (-987 2358);
FORCEPROP 2 LAST CDS_LIB standard
J 0
(-925 2350);
DISPLAY INVISIBLE (-925 2350);
FORCEPROP 1 LAST BODY_TYPE PLUMBING
J 0
(-925 2400);
DISPLAY 0.872340 (-925 2400);
PAINT GREEN (-925 2400);
DISPLAY INVISIBLE (-925 2400);
FORCEPROP 1 LAST HDL_TAP TRUE
J 0
(-600 2225);
DISPLAY 0.872340 (-600 2225);
DISPLAY INVISIBLE (-600 2225);
FORCEPROP 1 LAST PATH I288
J 0
(-927 2350);
DISPLAY 0.872340 (-927 2350);
PAINT GREEN (-927 2350);
DISPLAY INVISIBLE (-927 2350);
FORCEADD TAP..1
(-725 2100);
FORCEPROP 3 LASTPIN (-775 2100) SIG_NAME P5E_CPU1_PE3_TX_C_DP<8>
J 0
(-765 2110);
DISPLAY 0.659574 (-765 2110);
PAINT MONO (-765 2110);
DISPLAY INVISIBLE (-765 2110);
FORCEPROP 1 LASTPIN (-775 2100) BN 8
J 0
(-787 2108);
DISPLAY 0.680851 (-787 2108);
PAINT GREEN (-787 2108);
FORCEPROP 2 LAST CDS_LIB standard
J 0
(-725 2100);
DISPLAY INVISIBLE (-725 2100);
FORCEPROP 1 LAST BODY_TYPE PLUMBING
J 0
(-725 2150);
DISPLAY 0.872340 (-725 2150);
PAINT GREEN (-725 2150);
DISPLAY INVISIBLE (-725 2150);
FORCEPROP 1 LAST HDL_TAP TRUE
J 0
(-400 1975);
DISPLAY 0.872340 (-400 1975);
DISPLAY INVISIBLE (-400 1975);
FORCEPROP 1 LAST PATH I289
J 0
(-727 2100);
DISPLAY 0.872340 (-727 2100);
PAINT GREEN (-727 2100);
DISPLAY INVISIBLE (-727 2100);
FORCEADD TAP..1
(-725 2300);
FORCEPROP 3 LASTPIN (-775 2300) SIG_NAME P5E_CPU1_PE3_TX_C_DP<9>
J 0
(-765 2310);
DISPLAY 0.659574 (-765 2310);
PAINT MONO (-765 2310);
DISPLAY INVISIBLE (-765 2310);
FORCEPROP 1 LASTPIN (-775 2300) BN 9
J 0
(-787 2308);
DISPLAY 0.680851 (-787 2308);
PAINT GREEN (-787 2308);
FORCEPROP 2 LAST CDS_LIB standard
J 0
(-725 2300);
DISPLAY INVISIBLE (-725 2300);
FORCEPROP 1 LAST BODY_TYPE PLUMBING
J 0
(-725 2350);
DISPLAY 0.872340 (-725 2350);
PAINT GREEN (-725 2350);
DISPLAY INVISIBLE (-725 2350);
FORCEPROP 1 LAST HDL_TAP TRUE
J 0
(-400 2175);
DISPLAY 0.872340 (-400 2175);
DISPLAY INVISIBLE (-400 2175);
FORCEPROP 1 LAST PATH I290
J 0
(-727 2300);
DISPLAY 0.872340 (-727 2300);
PAINT GREEN (-727 2300);
DISPLAY INVISIBLE (-727 2300);
FORCEADD TAP..1
(-725 2500);
FORCEPROP 3 LASTPIN (-775 2500) SIG_NAME P5E_CPU1_PE3_TX_C_DP<10>
J 0
(-765 2510);
DISPLAY 0.659574 (-765 2510);
PAINT MONO (-765 2510);
DISPLAY INVISIBLE (-765 2510);
FORCEPROP 1 LASTPIN (-775 2500) BN 10
J 0
(-787 2508);
DISPLAY 0.680851 (-787 2508);
PAINT GREEN (-787 2508);
FORCEPROP 2 LAST CDS_LIB standard
J 0
(-725 2500);
DISPLAY INVISIBLE (-725 2500);
FORCEPROP 1 LAST BODY_TYPE PLUMBING
J 0
(-725 2550);
DISPLAY 0.872340 (-725 2550);
PAINT GREEN (-725 2550);
DISPLAY INVISIBLE (-725 2550);
FORCEPROP 1 LAST HDL_TAP TRUE
J 0
(-400 2375);
DISPLAY 0.872340 (-400 2375);
DISPLAY INVISIBLE (-400 2375);
FORCEPROP 1 LAST PATH I291
J 0
(-727 2500);
DISPLAY 0.872340 (-727 2500);
PAINT GREEN (-727 2500);
DISPLAY INVISIBLE (-727 2500);
FORCEADD TAP..1
(-925 2550);
FORCEPROP 3 LASTPIN (-975 2550) SIG_NAME P5E_CPU1_PE3_TX_C_DN<10>
J 0
(-965 2560);
DISPLAY 0.659574 (-965 2560);
PAINT MONO (-965 2560);
DISPLAY INVISIBLE (-965 2560);
FORCEPROP 1 LASTPIN (-975 2550) BN 10
J 0
(-987 2558);
DISPLAY 0.680851 (-987 2558);
PAINT GREEN (-987 2558);
FORCEPROP 2 LAST CDS_LIB standard
J 0
(-925 2550);
DISPLAY INVISIBLE (-925 2550);
FORCEPROP 1 LAST BODY_TYPE PLUMBING
J 0
(-925 2600);
DISPLAY 0.872340 (-925 2600);
PAINT GREEN (-925 2600);
DISPLAY INVISIBLE (-925 2600);
FORCEPROP 1 LAST HDL_TAP TRUE
J 0
(-600 2425);
DISPLAY 0.872340 (-600 2425);
DISPLAY INVISIBLE (-600 2425);
FORCEPROP 1 LAST PATH I292
J 0
(-927 2550);
DISPLAY 0.872340 (-927 2550);
PAINT GREEN (-927 2550);
DISPLAY INVISIBLE (-927 2550);
FORCEADD TAP..1
(-925 2750);
FORCEPROP 3 LASTPIN (-975 2750) SIG_NAME P5E_CPU1_PE3_TX_C_DN<11>
J 0
(-965 2760);
DISPLAY 0.659574 (-965 2760);
PAINT MONO (-965 2760);
DISPLAY INVISIBLE (-965 2760);
FORCEPROP 1 LASTPIN (-975 2750) BN 11
J 0
(-987 2758);
DISPLAY 0.680851 (-987 2758);
PAINT GREEN (-987 2758);
FORCEPROP 2 LAST CDS_LIB standard
J 0
(-925 2750);
DISPLAY INVISIBLE (-925 2750);
FORCEPROP 1 LAST BODY_TYPE PLUMBING
J 0
(-925 2800);
DISPLAY 0.872340 (-925 2800);
PAINT GREEN (-925 2800);
DISPLAY INVISIBLE (-925 2800);
FORCEPROP 1 LAST HDL_TAP TRUE
J 0
(-600 2625);
DISPLAY 0.872340 (-600 2625);
DISPLAY INVISIBLE (-600 2625);
FORCEPROP 1 LAST PATH I293
J 0
(-927 2750);
DISPLAY 0.872340 (-927 2750);
PAINT GREEN (-927 2750);
DISPLAY INVISIBLE (-927 2750);
FORCEADD TAP..1
(-925 2950);
FORCEPROP 3 LASTPIN (-975 2950) SIG_NAME P5E_CPU1_PE3_TX_C_DN<12>
J 0
(-965 2960);
DISPLAY 0.659574 (-965 2960);
PAINT MONO (-965 2960);
DISPLAY INVISIBLE (-965 2960);
FORCEPROP 1 LASTPIN (-975 2950) BN 12
J 0
(-987 2958);
DISPLAY 0.680851 (-987 2958);
PAINT GREEN (-987 2958);
FORCEPROP 2 LAST CDS_LIB standard
J 0
(-925 2950);
DISPLAY INVISIBLE (-925 2950);
FORCEPROP 1 LAST BODY_TYPE PLUMBING
J 0
(-925 3000);
DISPLAY 0.872340 (-925 3000);
PAINT GREEN (-925 3000);
DISPLAY INVISIBLE (-925 3000);
FORCEPROP 1 LAST HDL_TAP TRUE
J 0
(-600 2825);
DISPLAY 0.872340 (-600 2825);
DISPLAY INVISIBLE (-600 2825);
FORCEPROP 1 LAST PATH I294
J 0
(-927 2950);
DISPLAY 0.872340 (-927 2950);
PAINT GREEN (-927 2950);
DISPLAY INVISIBLE (-927 2950);
FORCEADD TAP..1
(-725 2700);
FORCEPROP 3 LASTPIN (-775 2700) SIG_NAME P5E_CPU1_PE3_TX_C_DP<11>
J 0
(-765 2710);
DISPLAY 0.659574 (-765 2710);
PAINT MONO (-765 2710);
DISPLAY INVISIBLE (-765 2710);
FORCEPROP 1 LASTPIN (-775 2700) BN 11
J 0
(-787 2708);
DISPLAY 0.680851 (-787 2708);
PAINT GREEN (-787 2708);
FORCEPROP 2 LAST CDS_LIB standard
J 0
(-725 2700);
DISPLAY INVISIBLE (-725 2700);
FORCEPROP 1 LAST BODY_TYPE PLUMBING
J 0
(-725 2750);
DISPLAY 0.872340 (-725 2750);
PAINT GREEN (-725 2750);
DISPLAY INVISIBLE (-725 2750);
FORCEPROP 1 LAST HDL_TAP TRUE
J 0
(-400 2575);
DISPLAY 0.872340 (-400 2575);
DISPLAY INVISIBLE (-400 2575);
FORCEPROP 1 LAST PATH I295
J 0
(-727 2700);
DISPLAY 0.872340 (-727 2700);
PAINT GREEN (-727 2700);
DISPLAY INVISIBLE (-727 2700);
FORCEADD TAP..1
(-725 2900);
FORCEPROP 3 LASTPIN (-775 2900) SIG_NAME P5E_CPU1_PE3_TX_C_DP<12>
J 0
(-765 2910);
DISPLAY 0.659574 (-765 2910);
PAINT MONO (-765 2910);
DISPLAY INVISIBLE (-765 2910);
FORCEPROP 1 LASTPIN (-775 2900) BN 12
J 0
(-787 2908);
DISPLAY 0.680851 (-787 2908);
PAINT GREEN (-787 2908);
FORCEPROP 2 LAST CDS_LIB standard
J 0
(-725 2900);
DISPLAY INVISIBLE (-725 2900);
FORCEPROP 1 LAST BODY_TYPE PLUMBING
J 0
(-725 2950);
DISPLAY 0.872340 (-725 2950);
PAINT GREEN (-725 2950);
DISPLAY INVISIBLE (-725 2950);
FORCEPROP 1 LAST HDL_TAP TRUE
J 0
(-400 2775);
DISPLAY 0.872340 (-400 2775);
DISPLAY INVISIBLE (-400 2775);
FORCEPROP 1 LAST PATH I296
J 0
(-727 2900);
DISPLAY 0.872340 (-727 2900);
PAINT GREEN (-727 2900);
DISPLAY INVISIBLE (-727 2900);
FORCEADD Q_CAP_DIFFBUS..2
R 2
(-1475 3150);
FORCEPROP 1 LAST PART_NUMBER SP_CH4221MEE01
J 2
(-1591 3238);
DISPLAY 0.574468 (-1591 3238);
PAINT GREEN (-1591 3238);
DISPLAY INVISIBLE (-1591 3238);
FORCEPROP 2 LAST VALUE DIFF BUS_0.22UF
J 2
(-1625 3150);
DISPLAY 0.553191 (-1625 3150);
FORCEPROP 1 LAST $LOCATION C1520
J 2
(-1225 3175);
DISPLAY 0.723404 (-1225 3175);
PAINT GREEN (-1225 3175);
FORCEPROP 2 LASTPIN (-1400 3150) $PN 1
J 0
(-1390 3160);
DISPLAY 0.808511 (-1390 3160);
FORCEPROP 2 LASTPIN (-1550 3150) $PN 2
J 2
(-1560 3160);
DISPLAY 0.808511 (-1560 3160);
FORCEPROP 2 LAST TOLERANCE 20%
J 2
(-1550 3200);
DISPLAY 0.553191 (-1550 3200);
DISPLAY INVISIBLE (-1550 3200);
FORCEPROP 2 LAST PACK_TYPE C0201
J 2
(-1650 3200);
DISPLAY 0.553191 (-1650 3200);
DISPLAY INVISIBLE (-1650 3200);
FORCEPROP 1 LAST MATERIAL X6S
J 2
(-1466 3229);
DISPLAY 0.574468 (-1466 3229);
PAINT GREEN (-1466 3229);
DISPLAY INVISIBLE (-1466 3229);
FORCEPROP 2 LAST VOLTAGE 6.3V
J 2
(-1825 3200);
DISPLAY 0.553191 (-1825 3200);
DISPLAY INVISIBLE (-1825 3200);
FORCEPROP 1 LAST PIN_NAMES_ROTATE TRUE
J 2
(-1475 3150);
DISPLAY 0.489362 (-1475 3150);
PAINT GREEN (-1475 3150);
DISPLAY INVISIBLE (-1475 3150);
FORCEPROP 2 LAST CDS_LIB pure_quanta
J 2
(-1475 3150);
DISPLAY INVISIBLE (-1475 3150);
FORCEPROP 1 LAST CDS_LMAN_SYM_OUTLINE -25,50,25,-50
J 2
(-1475 3150);
DISPLAY 0.468085 (-1475 3150);
PAINT GREEN (-1475 3150);
DISPLAY INVISIBLE (-1475 3150);
FORCEPROP 1 LAST PATH I297
J 2
(-1475 3150);
DISPLAY 0.723404 (-1475 3150);
DISPLAY INVISIBLE (-1475 3150);
FORCEPROP 0 LAST CDS_LOCATION C1520
J 0
(-1225 3225);
DISPLAY 1.021277 (-1225 3225);
DISPLAY INVISIBLE (-1225 3225);
FORCEPROP 2 LAST $SEC 1
J 2
(-1300 3225);
DISPLAY 0.680851 (-1300 3225);
PAINT MONO (-1300 3225);
DISPLAY INVISIBLE (-1300 3225);
FORCEPROP 2 LAST CDS_SEC 1
J 2
(-1300 3225);
DISPLAY 0.680851 (-1300 3225);
DISPLAY INVISIBLE (-1300 3225);
FORCEADD Q_CAP_DIFFBUS..2
R 2
(-1475 3100);
FORCEPROP 1 LAST PART_NUMBER SP_CH4221MEE01
J 2
(-1591 3188);
DISPLAY 0.574468 (-1591 3188);
PAINT GREEN (-1591 3188);
DISPLAY INVISIBLE (-1591 3188);
FORCEPROP 2 LAST VALUE DIFF BUS_0.22UF
J 2
(-1625 3100);
DISPLAY 0.553191 (-1625 3100);
FORCEPROP 1 LAST $LOCATION C1521
J 2
(-1225 3125);
DISPLAY 0.723404 (-1225 3125);
PAINT GREEN (-1225 3125);
FORCEPROP 2 LASTPIN (-1400 3100) $PN 1
J 0
(-1390 3110);
DISPLAY 0.808511 (-1390 3110);
FORCEPROP 2 LASTPIN (-1550 3100) $PN 2
J 2
(-1560 3110);
DISPLAY 0.808511 (-1560 3110);
FORCEPROP 2 LAST TOLERANCE 20%
J 2
(-1550 3150);
DISPLAY 0.553191 (-1550 3150);
DISPLAY INVISIBLE (-1550 3150);
FORCEPROP 2 LAST PACK_TYPE C0201
J 2
(-1650 3150);
DISPLAY 0.553191 (-1650 3150);
DISPLAY INVISIBLE (-1650 3150);
FORCEPROP 1 LAST MATERIAL X6S
J 2
(-1466 3179);
DISPLAY 0.574468 (-1466 3179);
PAINT GREEN (-1466 3179);
DISPLAY INVISIBLE (-1466 3179);
FORCEPROP 2 LAST VOLTAGE 6.3V
J 2
(-1825 3150);
DISPLAY 0.553191 (-1825 3150);
DISPLAY INVISIBLE (-1825 3150);
FORCEPROP 1 LAST PIN_NAMES_ROTATE TRUE
J 2
(-1475 3100);
DISPLAY 0.489362 (-1475 3100);
PAINT GREEN (-1475 3100);
DISPLAY INVISIBLE (-1475 3100);
FORCEPROP 2 LAST CDS_LIB pure_quanta
J 2
(-1475 3100);
DISPLAY INVISIBLE (-1475 3100);
FORCEPROP 1 LAST CDS_LMAN_SYM_OUTLINE -25,50,25,-50
J 2
(-1475 3100);
DISPLAY 0.468085 (-1475 3100);
PAINT GREEN (-1475 3100);
DISPLAY INVISIBLE (-1475 3100);
FORCEPROP 1 LAST PATH I298
J 2
(-1475 3100);
DISPLAY 0.723404 (-1475 3100);
DISPLAY INVISIBLE (-1475 3100);
FORCEPROP 0 LAST CDS_LOCATION C1521
J 0
(-1225 3175);
DISPLAY 1.021277 (-1225 3175);
DISPLAY INVISIBLE (-1225 3175);
FORCEPROP 2 LAST $SEC 1
J 2
(-1300 3175);
DISPLAY 0.680851 (-1300 3175);
PAINT MONO (-1300 3175);
DISPLAY INVISIBLE (-1300 3175);
FORCEPROP 2 LAST CDS_SEC 1
J 2
(-1300 3175);
DISPLAY 0.680851 (-1300 3175);
DISPLAY INVISIBLE (-1300 3175);
FORCEADD Q_CAP_DIFFBUS..2
R 2
(-1475 3300);
FORCEPROP 1 LAST PART_NUMBER SP_CH4221MEE01
J 2
(-1591 3388);
DISPLAY 0.574468 (-1591 3388);
PAINT GREEN (-1591 3388);
DISPLAY INVISIBLE (-1591 3388);
FORCEPROP 2 LAST VALUE DIFF BUS_0.22UF
J 2
(-1625 3300);
DISPLAY 0.553191 (-1625 3300);
FORCEPROP 1 LAST $LOCATION C1519
J 2
(-1225 3325);
DISPLAY 0.723404 (-1225 3325);
PAINT GREEN (-1225 3325);
FORCEPROP 2 LASTPIN (-1400 3300) $PN 1
J 0
(-1390 3310);
DISPLAY 0.808511 (-1390 3310);
FORCEPROP 2 LASTPIN (-1550 3300) $PN 2
J 2
(-1560 3310);
DISPLAY 0.808511 (-1560 3310);
FORCEPROP 2 LAST TOLERANCE 20%
J 2
(-1550 3350);
DISPLAY 0.553191 (-1550 3350);
DISPLAY INVISIBLE (-1550 3350);
FORCEPROP 2 LAST PACK_TYPE C0201
J 2
(-1650 3350);
DISPLAY 0.553191 (-1650 3350);
DISPLAY INVISIBLE (-1650 3350);
FORCEPROP 1 LAST MATERIAL X6S
J 2
(-1466 3379);
DISPLAY 0.574468 (-1466 3379);
PAINT GREEN (-1466 3379);
DISPLAY INVISIBLE (-1466 3379);
FORCEPROP 2 LAST VOLTAGE 6.3V
J 2
(-1825 3350);
DISPLAY 0.553191 (-1825 3350);
DISPLAY INVISIBLE (-1825 3350);
FORCEPROP 1 LAST PIN_NAMES_ROTATE TRUE
J 2
(-1475 3300);
DISPLAY 0.489362 (-1475 3300);
PAINT GREEN (-1475 3300);
DISPLAY INVISIBLE (-1475 3300);
FORCEPROP 2 LAST CDS_LIB pure_quanta
J 2
(-1475 3300);
DISPLAY INVISIBLE (-1475 3300);
FORCEPROP 1 LAST CDS_LMAN_SYM_OUTLINE -25,50,25,-50
J 2
(-1475 3300);
DISPLAY 0.468085 (-1475 3300);
PAINT GREEN (-1475 3300);
DISPLAY INVISIBLE (-1475 3300);
FORCEPROP 1 LAST PATH I299
J 2
(-1475 3300);
DISPLAY 0.723404 (-1475 3300);
DISPLAY INVISIBLE (-1475 3300);
FORCEPROP 0 LAST CDS_LOCATION C1519
J 0
(-1225 3375);
DISPLAY 1.021277 (-1225 3375);
DISPLAY INVISIBLE (-1225 3375);
FORCEPROP 2 LAST $SEC 1
J 2
(-1300 3375);
DISPLAY 0.680851 (-1300 3375);
PAINT MONO (-1300 3375);
DISPLAY INVISIBLE (-1300 3375);
FORCEPROP 2 LAST CDS_SEC 1
J 2
(-1300 3375);
DISPLAY 0.680851 (-1300 3375);
DISPLAY INVISIBLE (-1300 3375);
FORCEADD Q_CAP_DIFFBUS..2
R 2
(-1475 3350);
FORCEPROP 1 LAST PART_NUMBER SP_CH4221MEE01
J 2
(-1591 3438);
DISPLAY 0.574468 (-1591 3438);
PAINT GREEN (-1591 3438);
DISPLAY INVISIBLE (-1591 3438);
FORCEPROP 2 LAST VALUE DIFF BUS_0.22UF
J 2
(-1625 3350);
DISPLAY 0.553191 (-1625 3350);
FORCEPROP 1 LAST $LOCATION C1518
J 2
(-1225 3375);
DISPLAY 0.723404 (-1225 3375);
PAINT GREEN (-1225 3375);
FORCEPROP 2 LASTPIN (-1400 3350) $PN 1
J 0
(-1390 3360);
DISPLAY 0.808511 (-1390 3360);
FORCEPROP 2 LASTPIN (-1550 3350) $PN 2
J 2
(-1560 3360);
DISPLAY 0.808511 (-1560 3360);
FORCEPROP 2 LAST TOLERANCE 20%
J 2
(-1550 3400);
DISPLAY 0.553191 (-1550 3400);
DISPLAY INVISIBLE (-1550 3400);
FORCEPROP 2 LAST PACK_TYPE C0201
J 2
(-1650 3400);
DISPLAY 0.553191 (-1650 3400);
DISPLAY INVISIBLE (-1650 3400);
FORCEPROP 1 LAST MATERIAL X6S
J 2
(-1466 3429);
DISPLAY 0.574468 (-1466 3429);
PAINT GREEN (-1466 3429);
DISPLAY INVISIBLE (-1466 3429);
FORCEPROP 2 LAST VOLTAGE 6.3V
J 2
(-1825 3400);
DISPLAY 0.553191 (-1825 3400);
DISPLAY INVISIBLE (-1825 3400);
FORCEPROP 1 LAST PIN_NAMES_ROTATE TRUE
J 2
(-1475 3350);
DISPLAY 0.489362 (-1475 3350);
PAINT GREEN (-1475 3350);
DISPLAY INVISIBLE (-1475 3350);
FORCEPROP 2 LAST CDS_LIB pure_quanta
J 2
(-1475 3350);
DISPLAY INVISIBLE (-1475 3350);
FORCEPROP 1 LAST CDS_LMAN_SYM_OUTLINE -25,50,25,-50
J 2
(-1475 3350);
DISPLAY 0.468085 (-1475 3350);
PAINT GREEN (-1475 3350);
DISPLAY INVISIBLE (-1475 3350);
FORCEPROP 1 LAST PATH I300
J 2
(-1475 3350);
DISPLAY 0.723404 (-1475 3350);
DISPLAY INVISIBLE (-1475 3350);
FORCEPROP 0 LAST CDS_LOCATION C1518
J 0
(-1225 3425);
DISPLAY 1.021277 (-1225 3425);
DISPLAY INVISIBLE (-1225 3425);
FORCEPROP 2 LAST $SEC 1
J 2
(-1300 3425);
DISPLAY 0.680851 (-1300 3425);
PAINT MONO (-1300 3425);
DISPLAY INVISIBLE (-1300 3425);
FORCEPROP 2 LAST CDS_SEC 1
J 2
(-1300 3425);
DISPLAY 0.680851 (-1300 3425);
DISPLAY INVISIBLE (-1300 3425);
FORCEADD Q_CAP_DIFFBUS..2
R 2
(-1475 3500);
FORCEPROP 1 LAST PART_NUMBER SP_CH4221MEE01
J 2
(-1591 3588);
DISPLAY 0.574468 (-1591 3588);
PAINT GREEN (-1591 3588);
DISPLAY INVISIBLE (-1591 3588);
FORCEPROP 2 LAST VALUE DIFF BUS_0.22UF
J 2
(-1625 3500);
DISPLAY 0.553191 (-1625 3500);
FORCEPROP 1 LAST $LOCATION C1517
J 2
(-1225 3525);
DISPLAY 0.723404 (-1225 3525);
PAINT GREEN (-1225 3525);
FORCEPROP 2 LASTPIN (-1400 3500) $PN 1
J 0
(-1390 3510);
DISPLAY 0.808511 (-1390 3510);
FORCEPROP 2 LASTPIN (-1550 3500) $PN 2
J 2
(-1560 3510);
DISPLAY 0.808511 (-1560 3510);
FORCEPROP 2 LAST TOLERANCE 20%
J 2
(-1550 3550);
DISPLAY 0.553191 (-1550 3550);
DISPLAY INVISIBLE (-1550 3550);
FORCEPROP 2 LAST PACK_TYPE C0201
J 2
(-1650 3550);
DISPLAY 0.553191 (-1650 3550);
DISPLAY INVISIBLE (-1650 3550);
FORCEPROP 1 LAST MATERIAL X6S
J 2
(-1466 3579);
DISPLAY 0.574468 (-1466 3579);
PAINT GREEN (-1466 3579);
DISPLAY INVISIBLE (-1466 3579);
FORCEPROP 2 LAST VOLTAGE 6.3V
J 2
(-1825 3550);
DISPLAY 0.553191 (-1825 3550);
DISPLAY INVISIBLE (-1825 3550);
FORCEPROP 1 LAST PIN_NAMES_ROTATE TRUE
J 2
(-1475 3500);
DISPLAY 0.489362 (-1475 3500);
PAINT GREEN (-1475 3500);
DISPLAY INVISIBLE (-1475 3500);
FORCEPROP 2 LAST CDS_LIB pure_quanta
J 2
(-1475 3500);
DISPLAY INVISIBLE (-1475 3500);
FORCEPROP 1 LAST CDS_LMAN_SYM_OUTLINE -25,50,25,-50
J 2
(-1475 3500);
DISPLAY 0.468085 (-1475 3500);
PAINT GREEN (-1475 3500);
DISPLAY INVISIBLE (-1475 3500);
FORCEPROP 1 LAST PATH I301
J 2
(-1475 3500);
DISPLAY 0.723404 (-1475 3500);
DISPLAY INVISIBLE (-1475 3500);
FORCEPROP 0 LAST CDS_LOCATION C1517
J 0
(-1225 3575);
DISPLAY 1.021277 (-1225 3575);
DISPLAY INVISIBLE (-1225 3575);
FORCEPROP 2 LAST $SEC 1
J 2
(-1300 3575);
DISPLAY 0.680851 (-1300 3575);
PAINT MONO (-1300 3575);
DISPLAY INVISIBLE (-1300 3575);
FORCEPROP 2 LAST CDS_SEC 1
J 2
(-1300 3575);
DISPLAY 0.680851 (-1300 3575);
DISPLAY INVISIBLE (-1300 3575);
FORCEADD Q_CAP_DIFFBUS..2
R 2
(-1475 3550);
FORCEPROP 1 LAST PART_NUMBER SP_CH4221MEE01
J 2
(-1216 3638);
DISPLAY 0.574468 (-1216 3638);
PAINT GREEN (-1216 3638);
DISPLAY INVISIBLE (-1216 3638);
FORCEPROP 2 LAST VALUE DIFF BUS_0.22UF
J 2
(-1625 3550);
DISPLAY 0.553191 (-1625 3550);
FORCEPROP 2 LAST PACK_TYPE C0201
J 2
(-1475 3700);
DISPLAY 0.553191 (-1475 3700);
PAINT GREEN (-1475 3700);
FORCEPROP 1 LAST MATERIAL X6S
J 2
(-1516 3754);
DISPLAY 0.574468 (-1516 3754);
PAINT GREEN (-1516 3754);
FORCEPROP 2 LAST TOLERANCE 20%
J 2
(-1375 3700);
DISPLAY 0.553191 (-1375 3700);
PAINT GREEN (-1375 3700);
FORCEPROP 2 LAST VOLTAGE 6.3V
J 2
(-1225 3700);
DISPLAY 0.553191 (-1225 3700);
PAINT GREEN (-1225 3700);
FORCEPROP 1 LAST $LOCATION C1516
J 2
(-1225 3575);
DISPLAY 0.723404 (-1225 3575);
PAINT GREEN (-1225 3575);
FORCEPROP 2 LASTPIN (-1400 3550) $PN 1
J 0
(-1390 3560);
DISPLAY 0.808511 (-1390 3560);
FORCEPROP 2 LASTPIN (-1550 3550) $PN 2
J 2
(-1560 3560);
DISPLAY 0.808511 (-1560 3560);
FORCEPROP 1 LAST PIN_NAMES_ROTATE TRUE
J 2
(-1475 3550);
DISPLAY 0.489362 (-1475 3550);
PAINT GREEN (-1475 3550);
DISPLAY INVISIBLE (-1475 3550);
FORCEPROP 1 LAST CDS_LMAN_SYM_OUTLINE -25,50,25,-50
J 2
(-1475 3550);
DISPLAY 0.468085 (-1475 3550);
PAINT GREEN (-1475 3550);
DISPLAY INVISIBLE (-1475 3550);
FORCEPROP 2 LAST CDS_LIB pure_quanta
J 2
(-1475 3550);
DISPLAY INVISIBLE (-1475 3550);
FORCEPROP 1 LAST PATH I302
J 2
(-1475 3550);
DISPLAY 0.723404 (-1475 3550);
DISPLAY INVISIBLE (-1475 3550);
FORCEPROP 0 LAST CDS_LOCATION C1516
J 0
(-1500 3800);
DISPLAY 1.021277 (-1500 3800);
DISPLAY INVISIBLE (-1500 3800);
FORCEPROP 2 LAST $SEC 1
J 2
(-1300 3625);
DISPLAY 0.680851 (-1300 3625);
PAINT MONO (-1300 3625);
DISPLAY INVISIBLE (-1300 3625);
FORCEPROP 2 LAST CDS_SEC 1
J 2
(-1300 3625);
DISPLAY 0.680851 (-1300 3625);
DISPLAY INVISIBLE (-1300 3625);
FORCEADD TAP..1
(-925 3150);
FORCEPROP 3 LASTPIN (-975 3150) SIG_NAME P5E_CPU1_PE3_TX_C_DN<13>
J 0
(-965 3160);
DISPLAY 0.659574 (-965 3160);
PAINT MONO (-965 3160);
DISPLAY INVISIBLE (-965 3160);
FORCEPROP 1 LASTPIN (-975 3150) BN 13
J 0
(-987 3158);
DISPLAY 0.680851 (-987 3158);
PAINT GREEN (-987 3158);
FORCEPROP 2 LAST CDS_LIB standard
J 0
(-925 3150);
DISPLAY INVISIBLE (-925 3150);
FORCEPROP 1 LAST BODY_TYPE PLUMBING
J 0
(-925 3200);
DISPLAY 0.872340 (-925 3200);
PAINT GREEN (-925 3200);
DISPLAY INVISIBLE (-925 3200);
FORCEPROP 1 LAST HDL_TAP TRUE
J 0
(-600 3025);
DISPLAY 0.872340 (-600 3025);
DISPLAY INVISIBLE (-600 3025);
FORCEPROP 1 LAST PATH I303
J 0
(-927 3150);
DISPLAY 0.872340 (-927 3150);
PAINT GREEN (-927 3150);
DISPLAY INVISIBLE (-927 3150);
FORCEADD TAP..1
(-925 3350);
FORCEPROP 3 LASTPIN (-975 3350) SIG_NAME P5E_CPU1_PE3_TX_C_DN<14>
J 0
(-965 3360);
DISPLAY 0.659574 (-965 3360);
PAINT MONO (-965 3360);
DISPLAY INVISIBLE (-965 3360);
FORCEPROP 1 LASTPIN (-975 3350) BN 14
J 0
(-987 3358);
DISPLAY 0.680851 (-987 3358);
PAINT GREEN (-987 3358);
FORCEPROP 2 LAST CDS_LIB standard
J 0
(-925 3350);
DISPLAY INVISIBLE (-925 3350);
FORCEPROP 1 LAST BODY_TYPE PLUMBING
J 0
(-925 3400);
DISPLAY 0.872340 (-925 3400);
PAINT GREEN (-925 3400);
DISPLAY INVISIBLE (-925 3400);
FORCEPROP 1 LAST HDL_TAP TRUE
J 0
(-600 3225);
DISPLAY 0.872340 (-600 3225);
DISPLAY INVISIBLE (-600 3225);
FORCEPROP 1 LAST PATH I304
J 0
(-927 3350);
DISPLAY 0.872340 (-927 3350);
PAINT GREEN (-927 3350);
DISPLAY INVISIBLE (-927 3350);
FORCEADD TAP..1
(-925 3550);
FORCEPROP 3 LASTPIN (-975 3550) SIG_NAME P5E_CPU1_PE3_TX_C_DN<15>
J 0
(-965 3560);
DISPLAY 0.659574 (-965 3560);
PAINT MONO (-965 3560);
DISPLAY INVISIBLE (-965 3560);
FORCEPROP 1 LASTPIN (-975 3550) BN 15
J 0
(-987 3558);
DISPLAY 0.680851 (-987 3558);
PAINT GREEN (-987 3558);
FORCEPROP 2 LAST CDS_LIB standard
J 0
(-925 3550);
DISPLAY INVISIBLE (-925 3550);
FORCEPROP 1 LAST BODY_TYPE PLUMBING
J 0
(-925 3600);
DISPLAY 0.872340 (-925 3600);
PAINT GREEN (-925 3600);
DISPLAY INVISIBLE (-925 3600);
FORCEPROP 1 LAST HDL_TAP TRUE
J 0
(-600 3425);
DISPLAY 0.872340 (-600 3425);
DISPLAY INVISIBLE (-600 3425);
FORCEPROP 1 LAST PATH I305
J 0
(-927 3550);
DISPLAY 0.872340 (-927 3550);
PAINT GREEN (-927 3550);
DISPLAY INVISIBLE (-927 3550);
FORCEADD TAP..1
(-725 3100);
FORCEPROP 3 LASTPIN (-775 3100) SIG_NAME P5E_CPU1_PE3_TX_C_DP<13>
J 0
(-765 3110);
DISPLAY 0.659574 (-765 3110);
PAINT MONO (-765 3110);
DISPLAY INVISIBLE (-765 3110);
FORCEPROP 1 LASTPIN (-775 3100) BN 13
J 0
(-787 3108);
DISPLAY 0.680851 (-787 3108);
PAINT GREEN (-787 3108);
FORCEPROP 2 LAST CDS_LIB standard
J 0
(-725 3100);
DISPLAY INVISIBLE (-725 3100);
FORCEPROP 1 LAST BODY_TYPE PLUMBING
J 0
(-725 3150);
DISPLAY 0.872340 (-725 3150);
PAINT GREEN (-725 3150);
DISPLAY INVISIBLE (-725 3150);
FORCEPROP 1 LAST HDL_TAP TRUE
J 0
(-400 2975);
DISPLAY 0.872340 (-400 2975);
DISPLAY INVISIBLE (-400 2975);
FORCEPROP 1 LAST PATH I306
J 0
(-727 3100);
DISPLAY 0.872340 (-727 3100);
PAINT GREEN (-727 3100);
DISPLAY INVISIBLE (-727 3100);
FORCEADD TAP..1
(-725 3300);
FORCEPROP 3 LASTPIN (-775 3300) SIG_NAME P5E_CPU1_PE3_TX_C_DP<14>
J 0
(-765 3310);
DISPLAY 0.659574 (-765 3310);
PAINT MONO (-765 3310);
DISPLAY INVISIBLE (-765 3310);
FORCEPROP 1 LASTPIN (-775 3300) BN 14
J 0
(-787 3308);
DISPLAY 0.680851 (-787 3308);
PAINT GREEN (-787 3308);
FORCEPROP 2 LAST CDS_LIB standard
J 0
(-725 3300);
DISPLAY INVISIBLE (-725 3300);
FORCEPROP 1 LAST BODY_TYPE PLUMBING
J 0
(-725 3350);
DISPLAY 0.872340 (-725 3350);
PAINT GREEN (-725 3350);
DISPLAY INVISIBLE (-725 3350);
FORCEPROP 1 LAST HDL_TAP TRUE
J 0
(-400 3175);
DISPLAY 0.872340 (-400 3175);
DISPLAY INVISIBLE (-400 3175);
FORCEPROP 1 LAST PATH I307
J 0
(-727 3300);
DISPLAY 0.872340 (-727 3300);
PAINT GREEN (-727 3300);
DISPLAY INVISIBLE (-727 3300);
FORCEADD TAP..1
(-725 3500);
FORCEPROP 3 LASTPIN (-775 3500) SIG_NAME P5E_CPU1_PE3_TX_C_DP<15>
J 0
(-765 3510);
DISPLAY 0.659574 (-765 3510);
PAINT MONO (-765 3510);
DISPLAY INVISIBLE (-765 3510);
FORCEPROP 1 LASTPIN (-775 3500) BN 15
J 0
(-787 3508);
DISPLAY 0.680851 (-787 3508);
PAINT GREEN (-787 3508);
FORCEPROP 2 LAST CDS_LIB standard
J 0
(-725 3500);
DISPLAY INVISIBLE (-725 3500);
FORCEPROP 1 LAST BODY_TYPE PLUMBING
J 0
(-725 3550);
DISPLAY 0.872340 (-725 3550);
PAINT GREEN (-725 3550);
DISPLAY INVISIBLE (-725 3550);
FORCEPROP 1 LAST HDL_TAP TRUE
J 0
(-400 3375);
DISPLAY 0.872340 (-400 3375);
DISPLAY INVISIBLE (-400 3375);
FORCEPROP 1 LAST PATH I308
J 0
(-727 3500);
DISPLAY 0.872340 (-727 3500);
PAINT GREEN (-727 3500);
DISPLAY INVISIBLE (-727 3500);
FORCEADD OFFPAGE..2
(275 1600);
FORCEPROP 2 LAST $XR0 140 
J 0
(464 1600);
DISPLAY 0.638298 (464 1600);
PAINT MONO (464 1600);
FORCEPROP 2 LAST CDS_LIB standard
J 0
(275 1600);
DISPLAY INVISIBLE (275 1600);
FORCEPROP 1 LAST OFFPAGE TRUE
J 0
(600 1475);
DISPLAY 0.872340 (600 1475);
DISPLAY INVISIBLE (600 1475);
FORCEPROP 1 LAST COMMENT_BODY TRUE
J 0
(230 1505);
DISPLAY 0.872340 (230 1505);
PAINT GREEN (230 1505);
DISPLAY INVISIBLE (230 1505);
FORCEPROP 2 LAST PATH I309
J 0
(475 1650);
DISPLAY 1.021277 (475 1650);
DISPLAY INVISIBLE (475 1650);
FORCEADD OFFPAGE..2
(275 3525);
FORCEPROP 2 LAST $XR0 141 
J 0
(464 3525);
DISPLAY 0.638298 (464 3525);
PAINT MONO (464 3525);
FORCEPROP 2 LAST CDS_LIB standard
J 0
(275 3525);
DISPLAY INVISIBLE (275 3525);
FORCEPROP 1 LAST OFFPAGE TRUE
J 0
(600 3400);
DISPLAY 0.872340 (600 3400);
DISPLAY INVISIBLE (600 3400);
FORCEPROP 1 LAST COMMENT_BODY TRUE
J 0
(230 3430);
DISPLAY 0.872340 (230 3430);
PAINT GREEN (230 3430);
DISPLAY INVISIBLE (230 3430);
FORCEPROP 2 LAST PATH I310
J 0
(475 3575);
DISPLAY 1.021277 (475 3575);
DISPLAY INVISIBLE (475 3575);
FORCEADD OFFPAGE..2
(275 3575);
FORCEPROP 2 LAST $XR0 141 
J 0
(464 3575);
DISPLAY 0.638298 (464 3575);
PAINT MONO (464 3575);
FORCEPROP 2 LAST CDS_LIB standard
J 0
(275 3575);
DISPLAY INVISIBLE (275 3575);
FORCEPROP 1 LAST OFFPAGE TRUE
J 0
(600 3450);
DISPLAY 0.872340 (600 3450);
DISPLAY INVISIBLE (600 3450);
FORCEPROP 1 LAST COMMENT_BODY TRUE
J 0
(230 3480);
DISPLAY 0.872340 (230 3480);
PAINT GREEN (230 3480);
DISPLAY INVISIBLE (230 3480);
FORCEPROP 2 LAST PATH I311
J 0
(475 3625);
DISPLAY 1.021277 (475 3625);
DISPLAY INVISIBLE (475 3625);
FORCEADD OFFPAGE..2
(275 1550);
FORCEPROP 2 LAST $XR0 140 
J 0
(464 1550);
DISPLAY 0.638298 (464 1550);
PAINT MONO (464 1550);
FORCEPROP 2 LAST CDS_LIB standard
J 0
(275 1550);
DISPLAY INVISIBLE (275 1550);
FORCEPROP 1 LAST OFFPAGE TRUE
J 0
(600 1425);
DISPLAY 0.872340 (600 1425);
DISPLAY INVISIBLE (600 1425);
FORCEPROP 1 LAST COMMENT_BODY TRUE
J 0
(230 1455);
DISPLAY 0.872340 (230 1455);
PAINT GREEN (230 1455);
DISPLAY INVISIBLE (230 1455);
FORCEPROP 2 LAST PATH I312
J 0
(475 1600);
DISPLAY 1.021277 (475 1600);
DISPLAY INVISIBLE (475 1600);
FORCEADD QUANTA_TITLE_BLOCK_C..1
(5400 -1725);
FORCEPROP 0 LAST CDS_CON_LAST_MODIFIED Fri Aug 25 14:02:48 2023
J 0
(3515 -1710);
DISPLAY INVISIBLE (3515 -1710);
FORCEPROP 1 LAST CUSTOM_TXT_CDS <CON_LAST_MODIFIED>
J 0
(3515 -1710);
DISPLAY 0.978723 (3515 -1710);
FORCEPROP 2 LAST CUSTOM_TXT_CDS <XR_PAGE_TITLE>
J 0
(-2490 3525);
DISPLAY 0.638298 (-2490 3525);
PAINT PINK (-2490 3525);
DISPLAY INVISIBLE (-2490 3525);
FORCEPROP 2 LAST CUSTOM_TXT_CDS <Q_NUMBER>
J 0
(3997 -1622);
DISPLAY 1.212766 (3997 -1622);
FORCEPROP 1 LAST CUSTOM_TXT_CDS <NAME_2>
J 0
(2225 -1675);
FORCEPROP 1 LAST CUSTOM_TXT_CDS <NAME_1>
J 0
(2225 -1550);
FORCEPROP 1 LAST CUSTOM_TXT_CDS <Q_PROJ>
J 0
(3018 -1623);
DISPLAY 1.212766 (3018 -1623);
FORCEPROP 1 LAST CUSTOM_TXT_CDS <Q_REV>
J 0
(5216 -1622);
DISPLAY 1.212766 (5216 -1622);
FORCEPROP 1 LAST CUSTOM_TXT_CDS <CON_PAGE_NUM> OF <CON_TOTAL_PAGES>
J 0
(4954 -1707);
DISPLAY 0.978723 (4954 -1707);
FORCEPROP 1 LAST Q_TITLE PCIE AC-COUPLE CAPS 5/5
J 0
(-3966 -1699);
DISPLAY 2.446809 (-3966 -1699);
PAINT GREEN (-3966 -1699);
FORCEPROP 1 LAST Q_DEPT 
J 1
(1637 -1676);
DISPLAY 1.957447 (1637 -1676);
PAINT GREEN (1637 -1676);
FORCEPROP 2 LAST CDS_XR_PAGE_TITLE CR-177 : @S9S_MB_2U_LIB.S9S_MB_2U(SCH_1):PAGE177
J 0
(-2490 3525);
DISPLAY 0.638298 (-2490 3525);
PAINT PINK (-2490 3525);
DISPLAY INVISIBLE (-2490 3525);
FORCEPROP 2 LAST CDS_LIB pure_quanta
J 0
(5400 -1725);
DISPLAY INVISIBLE (5400 -1725);
FORCEPROP 1 LAST CDS_LMAN_SYM_OUTLINE -9475,6775,100,-125
J 0
(5400 -1725);
DISPLAY 0.468085 (5400 -1725);
PAINT GREEN (5400 -1725);
DISPLAY INVISIBLE (5400 -1725);
FORCEPROP 1 LAST COMMENT_BODY TRUE
J 0
(5412 -1738);
DISPLAY 0.978723 (5412 -1738);
PAINT GREEN (5412 -1738);
DISPLAY INVISIBLE (5412 -1738);
FORCEPROP 2 LAST PAGE_BORDER TRUE
J 0
(-2490 3525);
DISPLAY 0.638298 (-2490 3525);
PAINT PINK (-2490 3525);
DISPLAY INVISIBLE (-2490 3525);
WIRE 17 -1 (2375 2775)(2375 2975);
WIRE 17 -1 (2375 2775)(2375 2575);
WIRE 17 -1 (2375 3175)(2375 2975);
WIRE 17 -1 (2375 3375)(2375 3175);
WIRE 17 -1 (2375 2575)(2375 2375);
WIRE 17 -1 (2375 2375)(2375 2175);
WIRE 17 -1 (2375 3575)(2375 3375);
WIRE 17 -1 (1275 3575)(2375 3575);
FORCEPROP 2 LAST SIG_NAME P5E_CPU1_PE4_TX_DN<15:8>
J 0
(1315 3585);
DISPLAY 0.680851 (1315 3585);
PAINT WHITE (1315 3585);
WIRE 17 -1 (3750 2775)(3750 2975);
WIRE 17 -1 (3750 2775)(3750 2575);
WIRE 17 -1 (3750 3175)(3750 2975);
WIRE 17 -1 (3750 3375)(3750 3175);
WIRE 17 -1 (3750 2575)(3750 2375);
WIRE 17 -1 (3750 2375)(3750 2175);
WIRE 17 -1 (3750 3575)(3750 3375);
WIRE 17 -1 (3750 3575)(4850 3575);
FORCEPROP 2 LAST SIG_NAME P5E_CPU1_PE4_TX_C_DN<15:8>
J 0
(3990 3585);
DISPLAY 0.680851 (3990 3585);
PAINT WHITE (3990 3585);
WIRE 17 -1 (2125 2525)(2125 2725);
WIRE 17 -1 (2125 2325)(2125 2525);
WIRE 17 -1 (2125 2725)(2125 2925);
WIRE 17 -1 (2125 2925)(2125 3125);
WIRE 17 -1 (2125 2125)(2125 2325);
WIRE 17 -1 (2125 3125)(2125 3325);
WIRE 17 -1 (2125 3325)(2125 3525);
WIRE 17 -1 (1275 3525)(2125 3525);
FORCEPROP 2 LAST SIG_NAME P5E_CPU1_PE4_TX_DP<15:8>
J 0
(1315 3535);
DISPLAY 0.680851 (1315 3535);
PAINT WHITE (1315 3535);
WIRE 17 -1 (3950 2725)(3950 2925);
WIRE 17 -1 (3950 2725)(3950 2525);
WIRE 17 -1 (3950 3125)(3950 2925);
WIRE 17 -1 (3950 3325)(3950 3125);
WIRE 17 -1 (3950 2525)(3950 2325);
WIRE 17 -1 (3950 2325)(3950 2125);
WIRE 17 -1 (3950 3525)(3950 3325);
WIRE 17 -1 (3950 3525)(4850 3525);
FORCEPROP 2 LAST SIG_NAME P5E_CPU1_PE4_TX_C_DP<15:8>
J 0
(3990 3535);
DISPLAY 0.680851 (3990 3535);
PAINT WHITE (3990 3535);
WIRE 17 -1 (2125 1350)(2125 1550);
WIRE 17 -1 (2125 1150)(2125 1350);
WIRE 17 -1 (1275 1550)(2125 1550);
FORCEPROP 2 LAST SIG_NAME P5E_CPU1_PE4_TX_DP<7:0>
J 0
(1315 1560);
DISPLAY 0.680851 (1315 1560);
PAINT WHITE (1315 1560);
WIRE 17 -1 (2125 950)(2125 1150);
WIRE 17 -1 (2125 150)(2125 350);
WIRE 17 -1 (2125 350)(2125 550);
WIRE 17 -1 (2125 550)(2125 750);
WIRE 17 -1 (2125 750)(2125 950);
WIRE 17 -1 (2375 400)(2375 200);
WIRE 17 -1 (2375 600)(2375 400);
WIRE 17 -1 (2375 800)(2375 600);
WIRE 17 -1 (2375 800)(2375 1000);
WIRE 17 -1 (2375 1200)(2375 1000);
WIRE 17 -1 (2375 1400)(2375 1200);
WIRE 17 -1 (2375 1600)(2375 1400);
WIRE 17 -1 (1275 1600)(2375 1600);
FORCEPROP 2 LAST SIG_NAME P5E_CPU1_PE4_TX_DN<7:0>
J 0
(1315 1610);
DISPLAY 0.680851 (1315 1610);
PAINT WHITE (1315 1610);
WIRE 17 -1 (3950 550)(3950 350);
WIRE 17 -1 (3950 750)(3950 550);
WIRE 17 -1 (3950 350)(3950 150);
WIRE 17 -1 (3950 750)(3950 950);
WIRE 17 -1 (3950 1150)(3950 950);
WIRE 17 -1 (3950 1350)(3950 1150);
WIRE 17 -1 (3950 1550)(3950 1350);
WIRE 17 -1 (3950 1550)(4850 1550);
FORCEPROP 2 LAST SIG_NAME P5E_CPU1_PE4_TX_C_DP<7:0>
J 0
(3990 1560);
DISPLAY 0.680851 (3990 1560);
PAINT WHITE (3990 1560);
WIRE 17 -1 (3750 800)(3750 1000);
WIRE 17 -1 (3750 800)(3750 600);
WIRE 17 -1 (3750 1200)(3750 1000);
WIRE 17 -1 (3750 1400)(3750 1200);
WIRE 17 -1 (3750 600)(3750 400);
WIRE 17 -1 (3750 400)(3750 200);
WIRE 17 -1 (3750 1600)(3750 1400);
WIRE 17 -1 (3750 1600)(4850 1600);
FORCEPROP 2 LAST SIG_NAME P5E_CPU1_PE4_TX_C_DN<7:0>
J 0
(3990 1610);
DISPLAY 0.680851 (3990 1610);
PAINT WHITE (3990 1610);
WIRE 17 -1 (-2500 150)(-2500 350);
WIRE 17 -1 (-2500 350)(-2500 550);
WIRE 17 -1 (-2500 550)(-2500 750);
WIRE 17 -1 (-2500 750)(-2500 950);
WIRE 17 -1 (-2500 950)(-2500 1150);
WIRE 17 -1 (-2500 1150)(-2500 1350);
WIRE 17 -1 (-2500 1350)(-2500 1550);
WIRE 17 -1 (-3350 1550)(-2500 1550);
FORCEPROP 2 LAST SIG_NAME P5E_CPU1_PE3_TX_DP<7:0>
J 0
(-3310 1560);
DISPLAY 0.680851 (-3310 1560);
PAINT WHITE (-3310 1560);
WIRE 17 -1 (-2250 400)(-2250 200);
WIRE 17 -1 (-2250 600)(-2250 400);
WIRE 17 -1 (-2250 800)(-2250 600);
WIRE 17 -1 (-2250 800)(-2250 1000);
WIRE 17 -1 (-2250 1200)(-2250 1000);
WIRE 17 -1 (-2250 1400)(-2250 1200);
WIRE 17 -1 (-2250 1600)(-2250 1400);
WIRE 17 -1 (-3350 1600)(-2250 1600);
FORCEPROP 2 LAST SIG_NAME P5E_CPU1_PE3_TX_DN<7:0>
J 0
(-3310 1610);
DISPLAY 0.680851 (-3310 1610);
PAINT WHITE (-3310 1610);
WIRE 17 -1 (-875 400)(-875 200);
WIRE 17 -1 (-875 600)(-875 400);
WIRE 17 -1 (-875 800)(-875 600);
WIRE 17 -1 (-875 800)(-875 1000);
WIRE 17 -1 (-875 1200)(-875 1000);
WIRE 17 -1 (-875 1400)(-875 1200);
WIRE 17 -1 (-875 1600)(-875 1400);
WIRE 17 -1 (-875 1600)(225 1600);
FORCEPROP 2 LAST SIG_NAME P5E_CPU1_PE3_TX_C_DN<7:0>
J 0
(-635 1610);
DISPLAY 0.680851 (-635 1610);
PAINT WHITE (-635 1610);
WIRE 17 -1 (-2500 3125)(-2500 3325);
WIRE 17 -1 (-2500 2925)(-2500 3125);
WIRE 17 -1 (-2500 3325)(-2500 3525);
WIRE 17 -1 (-3350 3525)(-2500 3525);
FORCEPROP 2 LAST SIG_NAME P5E_CPU1_PE3_TX_DP<15:8>
J 0
(-3310 3535);
DISPLAY 0.680851 (-3310 3535);
PAINT WHITE (-3310 3535);
WIRE 17 -1 (-2250 3575)(-2250 3375);
WIRE 17 -1 (-3350 3575)(-2250 3575);
FORCEPROP 2 LAST SIG_NAME P5E_CPU1_PE3_TX_DN<15:8>
J 0
(-3310 3585);
DISPLAY 0.680851 (-3310 3585);
PAINT WHITE (-3310 3585);
WIRE 17 -1 (-2250 3375)(-2250 3175);
WIRE 17 -1 (-2250 3175)(-2250 2975);
WIRE 17 -1 (-2250 2775)(-2250 2975);
WIRE 17 -1 (-2250 2775)(-2250 2575);
WIRE 17 -1 (-2250 2575)(-2250 2375);
WIRE 17 -1 (-2250 2375)(-2250 2175);
WIRE 17 -1 (-2500 2525)(-2500 2725);
WIRE 17 -1 (-2500 2325)(-2500 2525);
WIRE 17 -1 (-2500 2725)(-2500 2925);
WIRE 17 -1 (-2500 2125)(-2500 2325);
WIRE 17 -1 (-675 1550)(225 1550);
FORCEPROP 2 LAST SIG_NAME P5E_CPU1_PE3_TX_C_DP<7:0>
J 0
(-635 1560);
DISPLAY 0.680851 (-635 1560);
PAINT WHITE (-635 1560);
WIRE 17 -1 (-875 3375)(-875 3175);
WIRE 17 -1 (-875 3575)(-875 3375);
WIRE 17 -1 (-875 3175)(-875 2975);
WIRE 17 -1 (-875 2775)(-875 2975);
WIRE 17 -1 (-875 3575)(225 3575);
FORCEPROP 2 LAST SIG_NAME P5E_CPU1_PE3_TX_C_DN<15:8>
J 0
(-635 3585);
DISPLAY 0.680851 (-635 3585);
PAINT WHITE (-635 3585);
WIRE 17 -1 (-675 3325)(-675 3125);
WIRE 17 -1 (-675 3525)(-675 3325);
WIRE 17 -1 (-675 3125)(-675 2925);
WIRE 17 -1 (-675 2725)(-675 2925);
WIRE 17 -1 (-675 3525)(225 3525);
FORCEPROP 2 LAST SIG_NAME P5E_CPU1_PE3_TX_C_DP<15:8>
J 0
(-635 3535);
DISPLAY 0.680851 (-635 3535);
PAINT WHITE (-635 3535);
WIRE 17 -1 (-875 2575)(-875 2375);
WIRE 17 -1 (-875 2775)(-875 2575);
WIRE 17 -1 (-875 2375)(-875 2175);
WIRE 17 -1 (-675 2525)(-675 2325);
WIRE 17 -1 (-675 2725)(-675 2525);
WIRE 17 -1 (-675 2325)(-675 2125);
WIRE 17 -1 (-675 1350)(-675 1150);
WIRE 17 -1 (-675 1550)(-675 1350);
WIRE 17 -1 (-675 1150)(-675 950);
WIRE 17 -1 (-675 750)(-675 950);
WIRE 17 -1 (-675 750)(-675 550);
WIRE 17 -1 (-675 550)(-675 350);
WIRE 17 -1 (-675 350)(-675 150);
WIRE 16 -1 (-1400 975)(-975 975);
WIRE 16 -1 (3075 525)(2225 525);
WIRE 16 -1 (3075 575)(2475 575);
WIRE 16 -1 (-1400 1325)(-775 1325);
WIRE 16 -1 (-1550 2950)(-2150 2950);
WIRE 16 -1 (-1400 3300)(-775 3300);
WIRE 16 -1 (-1400 3350)(-975 3350);
WIRE 16 -1 (-1400 3500)(-775 3500);
WIRE 16 -1 (-1400 3550)(-975 3550);
WIRE 16 -1 (-1400 125)(-775 125);
WIRE 16 -1 (-1400 325)(-775 325);
WIRE 16 -1 (-1400 375)(-975 375);
WIRE 16 -1 (-1400 525)(-775 525);
WIRE 16 -1 (-1400 725)(-775 725);
WIRE 16 -1 (-1400 925)(-775 925);
WIRE 16 -1 (-1400 2100)(-775 2100);
WIRE 16 -1 (-1550 1125)(-2400 1125);
WIRE 16 -1 (-1400 775)(-975 775);
WIRE 16 -1 (-1400 575)(-975 575);
WIRE 16 -1 (-1550 325)(-2400 325);
WIRE 16 -1 (-1400 1175)(-975 1175);
WIRE 16 -1 (-1400 1125)(-775 1125);
WIRE 16 -1 (-1400 2700)(-775 2700);
WIRE 16 -1 (-1400 2900)(-775 2900);
WIRE 16 -1 (-1400 2500)(-775 2500);
WIRE 16 -1 (-1400 2300)(-775 2300);
WIRE 16 -1 (-1400 2950)(-975 2950);
WIRE 16 -1 (-1400 2750)(-975 2750);
WIRE 16 -1 (-1400 2550)(-975 2550);
WIRE 16 -1 (-1400 2150)(-975 2150);
WIRE 16 -1 (-1400 2350)(-975 2350);
WIRE 16 -1 (-1400 3100)(-775 3100);
WIRE 16 -1 (-1400 3150)(-975 3150);
WIRE 16 -1 (-1400 1525)(-775 1525);
WIRE 16 -1 (-1400 1575)(-975 1575);
WIRE 16 -1 (-1400 1375)(-975 1375);
WIRE 16 -1 (-1550 925)(-2400 925);
WIRE 16 -1 (-1550 1525)(-2400 1525);
WIRE 16 -1 (-1550 1325)(-2400 1325);
WIRE 16 -1 (-1550 725)(-2400 725);
WIRE 16 -1 (-1550 975)(-2150 975);
WIRE 16 -1 (-1550 775)(-2150 775);
WIRE 16 -1 (-1550 1575)(-2150 1575);
WIRE 16 -1 (-1550 1375)(-2150 1375);
WIRE 16 -1 (-1550 1175)(-2150 1175);
WIRE 16 -1 (-1550 2750)(-2150 2750);
WIRE 16 -1 (-1550 3300)(-2400 3300);
WIRE 16 -1 (-1550 3500)(-2400 3500);
WIRE 16 -1 (-1550 2100)(-2400 2100);
WIRE 16 -1 (-1550 2700)(-2400 2700);
WIRE 16 -1 (-1550 2300)(-2400 2300);
WIRE 16 -1 (-1550 2900)(-2400 2900);
WIRE 16 -1 (-1550 2500)(-2400 2500);
WIRE 16 -1 (-1550 2150)(-2150 2150);
WIRE 16 -1 (-1550 2350)(-2150 2350);
WIRE 16 -1 (-1550 2550)(-2150 2550);
WIRE 16 -1 (-1550 3350)(-2150 3350);
WIRE 16 -1 (-1550 3150)(-2150 3150);
WIRE 16 -1 (-1550 3550)(-2150 3550);
WIRE 16 -1 (-1550 3100)(-2400 3100);
WIRE 16 -1 (-1400 175)(-975 175);
WIRE 16 -1 (-1550 525)(-2400 525);
WIRE 16 -1 (-1550 575)(-2150 575);
WIRE 16 -1 (-1550 375)(-2150 375);
WIRE 16 -1 (-1550 175)(-2150 175);
WIRE 16 -1 (-1550 125)(-2400 125);
WIRE 16 -1 (3225 125)(3850 125);
WIRE 16 -1 (3225 175)(3650 175);
WIRE 16 -1 (3075 375)(2475 375);
WIRE 16 -1 (3075 725)(2225 725);
WIRE 16 -1 (3075 775)(2475 775);
WIRE 16 -1 (3075 925)(2225 925);
WIRE 16 -1 (3075 975)(2475 975);
WIRE 16 -1 (3225 3350)(3650 3350);
WIRE 16 -1 (3225 3150)(3650 3150);
WIRE 16 -1 (3225 3550)(3650 3550);
WIRE 16 -1 (3225 3500)(3850 3500);
WIRE 16 -1 (3225 3300)(3850 3300);
WIRE 16 -1 (3225 3100)(3850 3100);
WIRE 16 -1 (3225 2350)(3650 2350);
WIRE 16 -1 (3225 2150)(3650 2150);
WIRE 16 -1 (3225 2550)(3650 2550);
WIRE 16 -1 (3225 2950)(3650 2950);
WIRE 16 -1 (3225 2500)(3850 2500);
WIRE 16 -1 (3225 2900)(3850 2900);
WIRE 16 -1 (3225 2100)(3850 2100);
WIRE 16 -1 (3075 3550)(2475 3550);
WIRE 16 -1 (3075 3150)(2475 3150);
WIRE 16 -1 (3075 3350)(2475 3350);
WIRE 16 -1 (3075 2350)(2475 2350);
WIRE 16 -1 (3075 2900)(2225 2900);
WIRE 16 -1 (3075 2300)(2225 2300);
WIRE 16 -1 (3075 2700)(2225 2700);
WIRE 16 -1 (3075 3100)(2225 3100);
WIRE 16 -1 (3075 3500)(2225 3500);
WIRE 16 -1 (3075 3300)(2225 3300);
WIRE 16 -1 (3225 1175)(3650 1175);
WIRE 16 -1 (3225 1375)(3650 1375);
WIRE 16 -1 (3225 1575)(3650 1575);
WIRE 16 -1 (3225 1125)(3850 1125);
WIRE 16 -1 (3225 1525)(3850 1525);
WIRE 16 -1 (3225 1325)(3850 1325);
WIRE 16 -1 (3225 375)(3650 375);
WIRE 16 -1 (3225 575)(3650 575);
WIRE 16 -1 (3225 775)(3650 775);
WIRE 16 -1 (3225 925)(3850 925);
WIRE 16 -1 (3225 525)(3850 525);
WIRE 16 -1 (3225 725)(3850 725);
WIRE 16 -1 (3225 975)(3650 975);
WIRE 16 -1 (3225 325)(3850 325);
WIRE 16 -1 (3075 1175)(2475 1175);
WIRE 16 -1 (3075 1375)(2475 1375);
WIRE 16 -1 (3075 1575)(2475 1575);
WIRE 16 -1 (3075 175)(2475 175);
WIRE 16 -1 (3075 325)(2225 325);
WIRE 16 -1 (3075 125)(2225 125);
WIRE 16 -1 (3075 1325)(2225 1325);
WIRE 16 -1 (3075 1125)(2225 1125);
WIRE 16 -1 (3075 1525)(2225 1525);
WIRE 16 -1 (3075 2100)(2225 2100);
WIRE 16 -1 (3075 2150)(2475 2150);
WIRE 16 -1 (3225 2300)(3850 2300);
WIRE 16 -1 (3225 2700)(3850 2700);
WIRE 16 -1 (3075 2550)(2475 2550);
WIRE 16 -1 (3075 2500)(2225 2500);
WIRE 16 -1 (3075 2950)(2475 2950);
WIRE 16 -1 (3225 2750)(3650 2750);
WIRE 16 -1 (3075 2750)(2475 2750);
FORCENOTE
CPU1 PCIE4 TX
(1875 -500) 0;
DISPLAY LEFT (1875 -500);
DISPLAY 4.148936 (1875 -500);
PAINT WHITE (1875 -500);
FORCENOTE
CPU1 PCIE3 TX
(-2725 -500) 0;
DISPLAY LEFT (-2725 -500);
DISPLAY 4.148936 (-2725 -500);
PAINT WHITE (-2725 -500);
QUIT
